%FSTAX23Y23*%
%MOIN*%
%SFA1B1*%

%IPPOS*%
%ADD14C,0.010000*%
%ADD19C,0.005000*%
%ADD22C,0.008000*%
%ADD26R,0.028000X0.165000*%
%ADD27R,0.028000X0.126000*%
%ADD33R,0.057090X0.045280*%
%ADD35R,0.041340X0.043310*%
%ADD37R,0.043310X0.041340*%
%ADD77R,0.045280X0.057090*%
%ADD81R,0.082870X0.044090*%
%ADD142C,0.120000*%
%ADD162C,0.020000*%
%ADD166C,0.112000*%
%ADD167C,0.021660*%
%ADD168C,0.031500*%
%ADD169C,0.065980*%
%ADD170C,0.061020*%
%ADD171R,0.061020X0.061020*%
%ADD172C,0.075000*%
%ADD173C,0.098430*%
%ADD174O,0.196850X0.098430*%
%ADD175O,0.177170X0.088580*%
%ADD176O,0.088580X0.177170*%
%ADD177C,0.055000*%
%ADD178R,0.055000X0.055000*%
%ADD179C,0.050000*%
%ADD180C,0.250000*%
%ADD181C,0.016000*%
%ADD182C,0.032000*%
%ADD183C,0.200000*%
%ADD184R,0.025200X0.026770*%
%ADD185R,0.073820X0.067910*%
%LNtimingcard_pcb-1*%
%LPD*%
G36*
X04349Y04334D02*
X02014D01*
X02011Y04333*
X02009Y04331*
X02007Y04329*
X02006Y04326*
Y04293*
X02007Y0429*
X02007Y04289*
Y04226*
X02007Y04225*
X02006Y04222*
Y04186*
X02006Y04185*
X02007Y04184*
X02007Y04184*
X02007Y04183*
X02008Y04182*
X02008Y04181*
X02008Y04181*
X02009Y04181*
X02009Y0418*
X0201Y04179*
X02012Y04175*
X02008Y04167*
X02007Y04157*
X02008Y04148*
X02012Y04139*
X0201Y04135*
X02009Y04135*
X02009Y04134*
X02008Y04134*
X02008Y04134*
X02008Y04133*
X02007Y04131*
X02007Y04131*
X02007Y04131*
X02006Y0413*
X02006Y04128*
Y04086*
X02006Y04085*
X02007Y04084*
X02007Y04084*
X02007Y04083*
X02008Y04082*
X02008Y04081*
X02008Y04081*
X02009Y04081*
X02009Y0408*
X0201Y04079*
X02012Y04075*
X02008Y04067*
X02007Y04057*
X02008Y04048*
X02012Y04039*
X0201Y04035*
X02009Y04035*
X02009Y04034*
X02008Y04034*
X02008Y04034*
X02008Y04033*
X02007Y04031*
X02007Y04031*
X02007Y04031*
X02006Y0403*
X02006Y04028*
Y0385*
X02006Y03849*
X02007Y03847*
X02007Y03847*
X02007Y03847*
X02008Y03846*
X02009Y03844*
X02009Y03844*
X02009Y03844*
X0201Y03844*
X02011Y03843*
X02014Y03841*
X02013Y03836*
X02013Y03835*
X02013Y03834*
X02009Y03831*
X02004Y03832*
X01998Y03831*
X01993Y03827*
X01989Y03822*
X01988Y03816*
X01989Y03809*
X01993Y03804*
X01998Y038*
X02004Y03799*
X02006Y03798*
Y02718*
X02007Y02714*
X02009Y02712*
X02011Y0271*
X02014Y02709*
X02349*
X02352Y0271*
X02355Y02712*
X02357Y02714*
X02358Y02718*
Y02824*
X02396*
X02402Y02818*
Y02792*
X02403Y02789*
X02402Y02788*
X02404Y02782*
X02407Y02777*
X02413Y02773*
X02419Y02772*
X02425Y02773*
X0243Y02777*
X02431Y02777*
X02437Y02777*
X02443Y02766*
X02454Y02753*
X02467Y02742*
X02482Y02733*
X02497Y02727*
X02514Y02723*
X02531Y02721*
X02548Y02723*
X02564Y02727*
X0258Y02733*
X02595Y02742*
X02608Y02753*
X02619Y02766*
X02627Y0278*
X02634Y02796*
X02638Y02813*
X02639Y0283*
X02638Y02846*
X02634Y02863*
X02627Y02879*
X02619Y02893*
X02608Y02906*
X02595Y02917*
X0258Y02926*
X02564Y02933*
X02548Y02937*
X02531Y02938*
X02514Y02937*
X02497Y02933*
X02482Y02926*
X02467Y02917*
X02454Y02906*
X02443Y02893*
X02434Y02879*
X0243Y02867*
X02425Y02868*
Y02883*
X02358*
Y02907*
X02358*
Y0298*
X02358*
Y03012*
X02384*
Y03072*
X02358*
Y03091*
X02384*
Y03109*
X02405*
X02407Y03106*
X02408Y03106*
Y031*
X02405Y03098*
X024Y03091*
X02398Y03082*
X024Y03073*
X02405Y03065*
X02413Y0306*
X02422Y03058*
X02431Y0306*
X02438Y03065*
X02443Y03073*
X02445Y03082*
X02443Y03091*
X02438Y03098*
X02432Y03102*
X02431Y03105*
X02431Y03108*
X02433Y03112*
X02435Y03118*
X02433Y03124*
X0243Y0313*
X02424Y03133*
X02418Y03134*
X02413Y03133*
X02384*
Y03151*
X02358*
Y0317*
X02384*
Y03187*
X02403*
X02407Y03184*
X02414Y03183*
X0242Y03184*
X02425Y03188*
X02429Y03193*
X0243Y03199*
X02429Y03206*
X02425Y03211*
X02425Y03211*
X02426Y03217*
X02431Y03218*
X02438Y03223*
X02443Y0323*
X02445Y03239*
X02443Y03248*
X02438Y03256*
X02431Y03261*
X02422Y03263*
X02413Y03261*
X02405Y03256*
X024Y03248*
X02398Y03239*
X024Y0323*
X02405Y03223*
X02409Y0322*
X02408Y03215*
X02407Y03214*
X02403Y03212*
X02384*
Y0323*
X02358*
Y03249*
X02384*
Y03265*
X02397*
X02402Y03266*
X02407Y03269*
X02416Y03279*
X0242Y03279*
X02425Y03283*
X02428Y03288*
X0243Y03295*
X02428Y03301*
X02425Y03306*
X0242Y0331*
X02413Y03311*
X02407Y0331*
X02402Y03306*
X02398Y03301*
X02398Y03298*
X02392Y03292*
X02384*
Y03309*
X02358*
Y03322*
X02674Y03639*
X02674Y03639*
X02675Y03639*
X02675Y0364*
X02676Y03641*
X02676Y03642*
X02676Y03642*
X02679Y03644*
X02686Y03645*
X02691Y03649*
X02694Y03654*
X02695Y03659*
X02696Y03661*
X02698Y03664*
X02698Y03664*
X02699Y03664*
X027Y03665*
X02701Y03665*
X02701Y03666*
X02701Y03666*
X02713Y03677*
X0352*
X03522Y03672*
X0352Y03671*
X03516Y03666*
X03515Y0366*
X03516Y03653*
X0352Y03648*
X03525Y03644*
X03531Y03643*
X03538Y03644*
X03543Y03648*
X03546Y03653*
X03548Y0366*
X03546Y03666*
X03543Y03671*
X03541Y03672*
X03542Y03677*
X03804*
X03807Y03678*
X0381Y0368*
Y0368*
X03913Y03783*
X03915Y03786*
X03916Y03789*
X0392Y03793*
X03939*
X04041Y03692*
Y03651*
X04038Y03647*
X04037Y03641*
X04038Y03635*
X04042Y03629*
X04047Y03626*
X04053Y03625*
X0406Y03626*
X04065Y03629*
X04068Y03635*
X0407Y03641*
X04068Y03647*
X04066Y03651*
Y03697*
X04065Y03701*
X04062Y03705*
X03953Y03814*
X03952Y03815*
X03951Y03821*
X04068Y03937*
X04181*
X04341Y03777*
Y03662*
X0385Y03171*
X03845Y03174*
X03846Y03176*
X03844Y03182*
X03841Y03187*
X03836Y03191*
X03829Y03192*
X03823Y03191*
X03818Y03187*
X03814Y03182*
X03813Y03176*
X03814Y03169*
X03818Y03164*
X03823Y0316*
X03829Y03159*
X03831Y0316*
X03834Y03155*
X03824Y03146*
Y02201*
X04154Y01871*
X06687*
X06688Y01869*
X06693Y01865*
X06699Y01864*
X06706Y01865*
X06711Y01869*
X06712Y01871*
X06901*
Y01649*
X06637Y01385*
X06635Y01387*
X06628Y01388*
X06622Y01387*
X06617Y01383*
X06613Y01378*
X06612Y01372*
X06613Y01365*
X06615Y01363*
X06584Y01331*
X06582Y01329*
X06581Y01326*
Y01241*
X06582Y01237*
X06584Y01235*
X06644Y01175*
X06646Y01173*
X06649Y01172*
X06779*
X06782Y01173*
X06785Y01175*
X0693Y01319*
X06934Y01317*
Y01216*
X06329Y00611*
X03784*
X02638Y01757*
X02638Y01758*
X02641Y01763*
X02643Y0177*
X02641Y01776*
X02638Y01781*
X02633Y01785*
X02626Y01786*
X0262Y01785*
X02615Y01781*
X02614Y01781*
X02425Y0197*
X02424Y01973*
X02421Y01978*
X02416Y01982*
X02413Y01982*
X01355Y0304*
Y04162*
X01357Y04163*
X0136Y04168*
X01361Y04175*
X0136Y04181*
X01357Y04186*
X01355Y04187*
Y04341*
X01709*
X01712Y04336*
X01711Y04335*
X0171Y04329*
X01711Y04323*
X01715Y04317*
X0172Y04314*
X01726Y04313*
X01733Y04314*
X01738Y04317*
X01741Y04323*
X01743Y04329*
X01741Y04335*
X01741Y04336*
X01744Y04341*
X01771*
X01774Y04336*
X01773Y04335*
X01772Y04329*
X01773Y04323*
X01777Y04317*
X01782Y04314*
X01788Y04313*
X01795Y04314*
X018Y04317*
X01803Y04323*
X01805Y04329*
X01803Y04335*
X01803Y04336*
X01806Y04341*
X04349*
Y04334*
G37*
G36*
X06504Y04151D02*
Y04111D01*
X06503Y04106*
X06502Y04093*
X06503Y0408*
X06504Y04075*
Y0372*
X06501Y03716*
X06314Y03717*
X06313Y03717*
X06312Y03717*
X06311Y03717*
X0631Y03717*
X0631Y03716*
X06309Y03716*
X06309Y03715*
X06308Y03715*
X06307Y03714*
X06307Y03714*
X06306Y03712*
X06301Y03716*
X06294Y03717*
X06288Y03716*
X06286Y03714*
X06281Y03715*
X0628Y03715*
X0628Y03716*
X06279Y03716*
X06278Y03717*
X06278Y03717*
X06277Y03717*
X06276Y03717*
X06275Y03717*
X05989Y03719*
X05989*
X05989*
X05988Y03718*
X05986Y03718*
X05986Y03718*
X05986*
X05985Y03717*
X05984Y03716*
X05984Y03716*
X05984Y03716*
X05874Y03606*
X05872Y03604*
X05871Y03601*
Y03451*
X05872Y03447*
X05874Y03445*
X06326Y02992*
Y02397*
X06304Y02376*
X06289*
X06287Y02381*
X06289Y02384*
X06291Y02391*
X06289Y02397*
X06286Y02402*
X06281Y02406*
X06274Y02407*
X06268Y02406*
X06263Y02402*
X06259Y02397*
X06258Y02391*
X06259Y02384*
X06262Y02381*
X0626Y02376*
X04639*
X04349Y02666*
Y02712*
X04351Y02713*
X04354Y02718*
X04356Y02725*
X04354Y02731*
X04351Y02736*
X04349Y02737*
Y03133*
X0435Y03135*
X04349Y03136*
Y03781*
X04184Y03946*
X04064*
X03937Y03818*
X0384*
X03836Y03821*
X03829Y03822*
X03823Y03821*
X03818Y03817*
X03814Y03812*
X03813Y03806*
X03814Y03799*
X03818Y03794*
X03823Y0379*
X03829Y03789*
X03836Y0379*
X0384Y03793*
X03906*
X03907Y03789*
X03804Y03686*
X02709*
X02695Y03672*
X02691Y03672*
X02686Y03676*
X02679Y03677*
X02673Y03676*
X02668Y03672*
X02664Y03667*
X02663Y03661*
X02664Y03654*
X02668Y03649*
X02668Y03644*
X02349Y03326*
Y03309*
X02285*
Y03249*
X02349*
Y0323*
X02285*
Y0317*
X02349*
Y03151*
X02285*
Y03091*
X02349*
Y02718*
X02014*
Y03803*
X02016Y03804*
X02019Y03809*
X02021Y03816*
X02021Y03816*
X02021Y03817*
X02025Y0382*
X02029Y03819*
X02036Y0382*
X02041Y03824*
X02044Y03829*
X02046Y03836*
X02044Y03842*
X02041Y03847*
X02036Y03851*
X02029Y03852*
X02023Y03851*
X02019Y03848*
X02014Y0385*
Y04028*
X02019Y04031*
X02025Y04026*
X02034Y04023*
X02043Y04022*
X02052Y04023*
X02061Y04026*
X02068Y04032*
X02074Y04039*
X02077Y04048*
X02079Y04057*
X02077Y04067*
X02074Y04075*
X02068Y04083*
X02061Y04088*
X02052Y04092*
X02043Y04093*
X02034Y04092*
X02025Y04088*
X02019Y04084*
X02014Y04086*
Y04128*
X02019Y04131*
X02025Y04126*
X02034Y04123*
X02043Y04122*
X02052Y04123*
X02061Y04126*
X02068Y04132*
X02074Y04139*
X02077Y04148*
X02079Y04157*
X02077Y04167*
X02074Y04175*
X02068Y04183*
X02061Y04188*
X02052Y04192*
X02043Y04193*
X02034Y04192*
X02025Y04188*
X02019Y04184*
X02014Y04186*
Y04222*
X02078*
Y04293*
X02014*
Y04326*
X06329*
X06504Y04151*
G37*
G36*
X06275Y03709D02*
X06279Y03704D01*
X06278Y03701*
X06279Y03694*
X06283Y03689*
X06288Y03685*
X06294Y03684*
X06301Y03685*
X06306Y03689*
X06309Y03694*
X06311Y03701*
X0631Y03704*
X06314Y03709*
X07024Y03706*
X07087Y03643*
Y01488*
X06779Y01181*
X06649*
X06589Y01241*
Y01326*
X06621Y01357*
X06622Y01356*
X06628Y01355*
X06635Y01356*
X0664Y0136*
X06643Y01365*
X06645Y01372*
X06643Y01378*
X06643Y01379*
X06909Y01646*
Y01991*
X06819Y02081*
X06409*
X06399Y02091*
X06401Y02095*
X06402Y02095*
X06407Y02099*
X0641Y02104*
X06412Y02111*
X0641Y02117*
X06407Y02122*
X06402Y02126*
X06395Y02127*
X06389Y02126*
X06384Y02122*
X0638Y02117*
X0638Y02116*
X06375Y02115*
X06334Y02156*
Y02996*
X05879Y03451*
Y03601*
X05989Y03711*
X06275Y03709*
G37*
%LNtimingcard_pcb-2*%
%LPC*%
G36*
X01493Y04289D02*
X01422D01*
Y04218*
X01493*
Y04289*
G37*
G36*
X01569Y04187D02*
X01563Y04186D01*
X01558Y04182*
X01554Y04177*
X01553Y04171*
X01554Y04165*
X01558Y04159*
X01563Y04156*
X01569Y04154*
X01576Y04156*
X01581Y04159*
X01584Y04165*
X01586Y04171*
X01584Y04177*
X01581Y04182*
X01576Y04186*
X01569Y04187*
G37*
G36*
X01779Y04172D02*
X01773Y04171D01*
X01768Y04167*
X01764Y04162*
X01763Y04156*
X01764Y04149*
X01768Y04144*
X01773Y0414*
X01779Y04139*
X01786Y0414*
X01791Y04144*
X01794Y04149*
X01796Y04156*
X01794Y04162*
X01791Y04167*
X01786Y04171*
X01779Y04172*
G37*
G36*
X01457Y04189D02*
X01448Y04188D01*
X01439Y04184*
X01432Y04179*
X01426Y04171*
X01423Y04163*
X01421Y04153*
X01423Y04144*
X01426Y04136*
X01432Y04128*
X01439Y04122*
X01448Y04119*
X01457Y04118*
X01466Y04119*
X01475Y04122*
X01483Y04128*
X01488Y04136*
X01492Y04144*
X01493Y04153*
X01492Y04163*
X01488Y04171*
X01483Y04179*
X01475Y04184*
X01466Y04188*
X01457Y04189*
G37*
G36*
X01749Y04126D02*
X01743Y04125D01*
X01738Y04121*
X01734Y04116*
X01733Y0411*
X01734Y04103*
X01738Y04098*
X01743Y04094*
X01749Y04093*
X01756Y04094*
X01761Y04098*
X01764Y04103*
X01766Y0411*
X01764Y04116*
X01761Y04121*
X01756Y04125*
X01749Y04126*
G37*
G36*
X01691Y04095D02*
X01685Y04094D01*
X0168Y0409*
X01676Y04085*
X01675Y04079*
X01676Y04072*
X0168Y04067*
X01685Y04063*
X01691Y04062*
X01698Y04063*
X01703Y04067*
X01706Y04072*
X01708Y04079*
X01706Y04085*
X01703Y0409*
X01698Y04094*
X01691Y04095*
G37*
G36*
X01457Y04089D02*
X01448Y04088D01*
X01439Y04084*
X01432Y04079*
X01426Y04071*
X01423Y04063*
X01421Y04053*
X01423Y04044*
X01426Y04036*
X01432Y04028*
X01439Y04022*
X01448Y04019*
X01457Y04018*
X01466Y04019*
X01475Y04022*
X01483Y04028*
X01488Y04036*
X01492Y04044*
X01493Y04053*
X01492Y04063*
X01488Y04071*
X01483Y04079*
X01475Y04084*
X01466Y04088*
X01457Y04089*
G37*
G36*
X01903Y04034D02*
X01897Y04033D01*
X01892Y04029*
X01888Y04024*
X01887Y04018*
X01888Y04011*
X01892Y04006*
X01897Y04002*
X01903Y04001*
X0191Y04002*
X01915Y04006*
X01918Y04011*
X0192Y04018*
X01918Y04024*
X01915Y04029*
X0191Y04033*
X01903Y04034*
G37*
G36*
X01408Y03996D02*
X01402Y03995D01*
X01396Y03991*
X01393Y03986*
X01392Y0398*
X01393Y03974*
X01396Y03968*
X01402Y03965*
X01408Y03964*
X01414Y03965*
X0142Y03968*
X01423Y03974*
X01424Y0398*
X01423Y03986*
X0142Y03991*
X01414Y03995*
X01408Y03996*
G37*
G36*
X04085Y03908D02*
X04079Y03907D01*
X04074Y03903*
X0407Y03898*
X04069Y03892*
X0407Y03885*
X04074Y0388*
X04079Y03876*
X04085Y03875*
X04092Y03876*
X04097Y0388*
X041Y03885*
X04102Y03892*
X041Y03898*
X04097Y03903*
X04092Y03907*
X04085Y03908*
G37*
G36*
X04194Y039D02*
X04188Y03899D01*
X04183Y03895*
X04179Y0389*
X04178Y03884*
X04179Y03877*
X04183Y03872*
X04188Y03868*
X04194Y03867*
X04201Y03868*
X04206Y03872*
X04209Y03877*
X04211Y03884*
X04209Y0389*
X04206Y03895*
X04201Y03899*
X04194Y039*
G37*
G36*
X04039Y038D02*
X04033Y03799D01*
X04028Y03795*
X04024Y0379*
X04023Y03784*
X04024Y03777*
X04028Y03772*
X04033Y03768*
X04039Y03767*
X04046Y03768*
X04051Y03772*
X04054Y03777*
X04056Y03784*
X04054Y0379*
X04051Y03795*
X04046Y03799*
X04039Y038*
G37*
G36*
X01849Y03717D02*
X01843Y03716D01*
X01838Y03712*
X01834Y03707*
X01833Y03701*
X01834Y03694*
X01838Y03689*
X01843Y03685*
X01849Y03684*
X01856Y03685*
X01861Y03689*
X01864Y03694*
X01866Y03701*
X01864Y03707*
X01861Y03712*
X01856Y03716*
X01849Y03717*
G37*
G36*
X01754Y03677D02*
X01748Y03676D01*
X01743Y03672*
X01739Y03667*
X01738Y03661*
X01739Y03654*
X01743Y03649*
X01748Y03645*
X01754Y03644*
X01761Y03645*
X01766Y03649*
X01769Y03654*
X01771Y03661*
X01769Y03667*
X01766Y03672*
X01761Y03676*
X01754Y03677*
G37*
G36*
X03424Y03652D02*
X03418Y03651D01*
X03413Y03647*
X03409Y03642*
X03408Y03636*
X03409Y03629*
X03413Y03624*
X03418Y0362*
X03424Y03619*
X03431Y0362*
X03436Y03624*
X03439Y03629*
X03441Y03636*
X03439Y03642*
X03436Y03647*
X03431Y03651*
X03424Y03652*
G37*
G36*
X02799Y03632D02*
X02793Y03631D01*
X02788Y03627*
X02784Y03622*
X02783Y03616*
X02784Y03609*
X02788Y03604*
X02793Y036*
X02799Y03599*
X02806Y036*
X02811Y03604*
X02814Y03609*
X02816Y03616*
X02814Y03622*
X02811Y03627*
X02806Y03631*
X02799Y03632*
G37*
G36*
X01884Y03617D02*
X01878Y03616D01*
X01873Y03612*
X01869Y03607*
X01868Y03601*
X01869Y03594*
X01873Y03589*
X01878Y03585*
X01884Y03584*
X01891Y03585*
X01896Y03589*
X01899Y03594*
X01901Y03601*
X01899Y03607*
X01896Y03612*
X01891Y03616*
X01884Y03617*
G37*
G36*
X04116Y03614D02*
X0411Y03612D01*
X04105Y03609*
X04101Y03604*
X041Y03597*
X04101Y03591*
X04105Y03586*
X0411Y03582*
X04116Y03581*
X04122Y03582*
X04128Y03586*
X04131Y03591*
X04133Y03597*
X04131Y03604*
X04128Y03609*
X04122Y03612*
X04116Y03614*
G37*
G36*
X03239Y03612D02*
X03233Y03611D01*
X03228Y03607*
X03224Y03602*
X03223Y03596*
X03224Y03589*
X03228Y03584*
X03233Y0358*
X03239Y03579*
X03246Y0358*
X03251Y03584*
X03254Y03589*
X03256Y03596*
X03254Y03602*
X03251Y03607*
X03246Y03611*
X03239Y03612*
G37*
G36*
X01549Y03637D02*
X01543Y03636D01*
X01538Y03632*
X01534Y03627*
X01533Y03621*
X01534Y03614*
X01538Y03609*
X01543Y03605*
X01549Y03604*
X01556Y03605*
X01556Y03606*
X01559Y03602*
X01559Y03602*
X01558Y03596*
X01559Y03589*
X01563Y03584*
X01568Y0358*
X01574Y03579*
X01581Y0358*
X01586Y03584*
X01589Y03589*
X01591Y03596*
X01589Y03602*
X01586Y03607*
X01581Y03611*
X01574Y03612*
X01568Y03611*
X01568Y0361*
X01564Y03614*
X01564Y03614*
X01566Y03621*
X01564Y03627*
X01561Y03632*
X01556Y03636*
X01549Y03637*
G37*
G36*
X0144Y03573D02*
X01434Y03572D01*
X01429Y03568*
X01425Y03563*
X01424Y03557*
X01425Y0355*
X01429Y03545*
X01434Y03541*
X0144Y0354*
X01447Y03541*
X01452Y03545*
X01455Y0355*
X01457Y03557*
X01455Y03563*
X01452Y03568*
X01447Y03572*
X0144Y03573*
G37*
G36*
X02674Y03517D02*
X02668Y03516D01*
X02663Y03512*
X02659Y03507*
X02658Y03501*
X02659Y03494*
X02663Y03489*
X02668Y03485*
X02674Y03484*
X02681Y03485*
X02686Y03489*
X02689Y03494*
X02691Y03501*
X02689Y03507*
X02686Y03512*
X02681Y03516*
X02674Y03517*
G37*
G36*
X0272Y03511D02*
X02713Y03509D01*
X02708Y03506*
X02704Y03501*
X02703Y03494*
X02704Y03488*
X02708Y03483*
X02713Y03479*
X0272Y03478*
X02726Y03479*
X02731Y03483*
X02735Y03488*
X02736Y03494*
X02735Y03501*
X02731Y03506*
X02726Y03509*
X0272Y03511*
G37*
G36*
X03622Y03502D02*
X03616Y03501D01*
X03611Y03497*
X03607Y03492*
X03606Y03486*
X03607Y03479*
X03611Y03474*
X03616Y0347*
X03622Y03469*
X03629Y0347*
X03634Y03474*
X03637Y03479*
X03639Y03486*
X03637Y03492*
X03634Y03497*
X03629Y03501*
X03622Y03502*
G37*
G36*
X02579D02*
X02573Y03501D01*
X02568Y03497*
X02564Y03492*
X02563Y03486*
X02564Y03479*
X02568Y03474*
X02573Y0347*
X02579Y03469*
X02586Y0347*
X02591Y03474*
X02594Y03479*
X02596Y03486*
X02594Y03492*
X02591Y03497*
X02586Y03501*
X02579Y03502*
G37*
G36*
X03437Y03492D02*
X0343Y03491D01*
X03425Y03487*
X03421Y03482*
X0342Y03476*
X03421Y0347*
X03425Y03464*
X0343Y03461*
X03437Y0346*
X03443Y03461*
X03448Y03464*
X03452Y0347*
X03453Y03476*
X03452Y03482*
X03448Y03487*
X03443Y03491*
X03437Y03492*
G37*
G36*
X03469Y03472D02*
X03463Y03471D01*
X03458Y03467*
X03454Y03462*
X03453Y03456*
X03454Y03449*
X03458Y03444*
X03463Y0344*
X03469Y03439*
X03476Y0344*
X03481Y03444*
X03484Y03449*
X03486Y03456*
X03484Y03462*
X03481Y03467*
X03476Y03471*
X03469Y03472*
G37*
G36*
X03358Y03464D02*
X03352Y03463D01*
X03347Y03459*
X03343Y03454*
X03342Y03448*
X03343Y03441*
X03347Y03436*
X03352Y03432*
X03358Y03431*
X03365Y03432*
X0337Y03436*
X03373Y03441*
X03374Y03443*
X03379*
X03379Y0344*
X03383Y03435*
X03388Y03431*
X03394Y0343*
X03401Y03431*
X03406Y03435*
X03409Y0344*
X03411Y03447*
X03409Y03453*
X03406Y03458*
X03401Y03462*
X03394Y03463*
X03388Y03462*
X03383Y03458*
X03379Y03453*
X03379Y03451*
X03374*
X03373Y03454*
X0337Y03459*
X03365Y03463*
X03358Y03464*
G37*
G36*
X02634Y03422D02*
X02628Y03421D01*
X02623Y03417*
X02619Y03412*
X02618Y03406*
X02619Y03399*
X02623Y03394*
X02628Y0339*
X02634Y03389*
X02641Y0339*
X02646Y03394*
X02649Y03399*
X02651Y03406*
X02649Y03412*
X02646Y03417*
X02641Y03421*
X02634Y03422*
G37*
G36*
X0307Y0341D02*
X03064Y03408D01*
X03059Y03405*
X03055Y03399*
X03054Y03393*
X03055Y03387*
X03059Y03382*
X03064Y03378*
X0307Y03377*
X03077Y03378*
X03082Y03382*
X03085Y03387*
X03087Y03393*
X03085Y03399*
X03082Y03405*
X03077Y03408*
X0307Y0341*
G37*
G36*
X03302Y0336D02*
X03296Y03359D01*
X03291Y03355*
X03287Y0335*
X03286Y03344*
X03287Y03337*
X03291Y03332*
X03296Y03328*
X03302Y03327*
X03309Y03328*
X03314Y03332*
X03317Y03337*
X03319Y03344*
X03317Y0335*
X03314Y03355*
X03309Y03359*
X03302Y0336*
G37*
G36*
X03744Y03358D02*
X03738Y03357D01*
X03733Y03353*
X03729Y03348*
X03728Y03342*
X03729Y03335*
X03733Y0333*
X03738Y03326*
X03744Y03325*
X03751Y03326*
X03756Y0333*
X03759Y03335*
X03761Y03342*
X03759Y03348*
X03756Y03353*
X03751Y03357*
X03744Y03358*
G37*
G36*
X03542Y03334D02*
X03536Y03333D01*
X03531Y0333*
X03527Y03324*
X03526Y03318*
X03527Y03312*
X03531Y03307*
X03536Y03303*
X03542Y03302*
X03549Y03303*
X03554Y03307*
X03557Y03312*
X03559Y03318*
X03557Y03324*
X03554Y0333*
X03549Y03333*
X03542Y03334*
G37*
G36*
X03263Y0332D02*
X03257Y03318D01*
X03252Y03315*
X03248Y0331*
X03247Y03303*
X03248Y03297*
X03252Y03292*
X03257Y03288*
X03263Y03287*
X03269Y03288*
X03275Y03292*
X03278Y03297*
X0328Y03303*
X03278Y0331*
X03275Y03315*
X03269Y03318*
X03263Y0332*
G37*
G36*
X0333Y03317D02*
X03324Y03316D01*
X03319Y03312*
X03315Y03307*
X03314Y03301*
X03315Y03294*
X03319Y03289*
X03324Y03285*
X0333Y03284*
X03337Y03285*
X03342Y03289*
X03345Y03294*
X03347Y03301*
X03345Y03307*
X03342Y03312*
X03337Y03316*
X0333Y03317*
G37*
G36*
X03491Y03313D02*
X03485Y03312D01*
X0348Y03308*
X03476Y03303*
X03475Y03297*
X03476Y0329*
X0348Y03285*
X03485Y03281*
X03491Y0328*
X03498Y03281*
X03503Y03285*
X03506Y0329*
X03508Y03297*
X03506Y03303*
X03503Y03308*
X03498Y03312*
X03491Y03313*
G37*
G36*
X03657Y03312D02*
X03651Y03311D01*
X03646Y03307*
X03642Y03302*
X03641Y03296*
X03642Y0329*
X03646Y03284*
X03651Y03281*
X03657Y0328*
X03664Y03281*
X03669Y03284*
X03672Y0329*
X03674Y03296*
X03672Y03302*
X03669Y03307*
X03664Y03311*
X03657Y03312*
G37*
G36*
X03374Y03289D02*
X03368Y03288D01*
X03363Y03284*
X03359Y03279*
X03358Y03273*
X03359Y03266*
X03363Y03261*
X03368Y03257*
X03374Y03256*
X03381Y03257*
X03386Y03261*
X03389Y03266*
X03391Y03273*
X03389Y03279*
X03386Y03284*
X03381Y03288*
X03374Y03289*
G37*
G36*
X02559Y03309D02*
X0246D01*
Y03249*
X02559*
Y03266*
X02583*
X02588Y03267*
X02592Y0327*
X02594Y03272*
X02597Y03272*
X02602Y03276*
X02605Y03281*
X02607Y03288*
X02605Y03294*
X02602Y03299*
X02597Y03303*
X0259Y03304*
X02584Y03303*
X02579Y03299*
X02575Y03294*
X02575Y03291*
X02559*
Y03309*
G37*
G36*
X03744Y03277D02*
X03738Y03276D01*
X03733Y03272*
X03729Y03267*
X03728Y03261*
X03729Y03254*
X03733Y03249*
X03738Y03245*
X03744Y03244*
X03751Y03245*
X03756Y03249*
X03759Y03254*
X03761Y03261*
X03759Y03267*
X03756Y03272*
X03751Y03276*
X03744Y03277*
G37*
G36*
X0323Y03251D02*
X03224Y0325D01*
X03219Y03246*
X03215Y03241*
X03214Y03235*
X03215Y03228*
X03219Y03223*
X03224Y03219*
X0323Y03218*
X03237Y03219*
X03242Y03223*
X03245Y03228*
X03247Y03235*
X03245Y03241*
X03242Y03246*
X03237Y0325*
X0323Y03251*
G37*
G36*
X03806D02*
X038Y0325D01*
X03795Y03246*
X03791Y03241*
X0379Y03235*
X03791Y03228*
X03795Y03223*
X03797Y03222*
X03796Y03216*
X03793Y03216*
X03788Y03212*
X03784Y03207*
X03783Y03201*
X03784Y03194*
X03788Y03189*
X03793Y03185*
X03799Y03184*
X03806Y03185*
X03811Y03189*
X03814Y03194*
X03816Y03201*
X03814Y03207*
X03811Y03212*
X03809Y03214*
X0381Y03219*
X03813Y03219*
X03818Y03223*
X03821Y03228*
X03823Y03235*
X03821Y03241*
X03818Y03246*
X03813Y0325*
X03806Y03251*
G37*
G36*
X03188Y03203D02*
X03182Y03202D01*
X03177Y03198*
X03173Y03193*
X03172Y03187*
X03173Y0318*
X03177Y03175*
X03182Y03171*
X03188Y0317*
X03195Y03171*
X032Y03175*
X03204Y0318*
X03205Y03187*
X03204Y03193*
X032Y03198*
X03195Y03202*
X03188Y03203*
G37*
G36*
X01459Y03163D02*
X01453Y03162D01*
X01448Y03158*
X01444Y03153*
X01443Y03147*
X01444Y0314*
X01448Y03135*
X01453Y03131*
X01459Y0313*
X01466Y03131*
X01471Y03135*
X01474Y0314*
X01476Y03147*
X01474Y03153*
X01471Y03158*
X01466Y03162*
X01459Y03163*
G37*
G36*
X03275Y03158D02*
X03269Y03156D01*
X03264Y03153*
X0326Y03147*
X03259Y03141*
X0326Y03135*
X03264Y0313*
X03269Y03126*
X03275Y03125*
X03281Y03126*
X03287Y0313*
X0329Y03135*
X03291Y03141*
X0329Y03147*
X03287Y03153*
X03281Y03156*
X03275Y03158*
G37*
G36*
X03183Y03152D02*
X03176Y0315D01*
X03171Y03147*
X03168Y03142*
X03166Y03135*
X03168Y03129*
X03171Y03124*
X03176Y0312*
X03183Y03119*
X03189Y0312*
X03194Y03124*
X03198Y03129*
X03199Y03135*
X03198Y03142*
X03194Y03147*
X03189Y0315*
X03183Y03152*
G37*
G36*
X02559Y0323D02*
X0246D01*
Y03188*
X02456Y03187*
X0245Y03183*
X02447Y03178*
X02446Y03172*
X02447Y03166*
X0245Y0316*
X02456Y03157*
X02459Y03156*
X0246Y03151*
Y03151*
Y03091*
X02559*
Y03134*
X02595Y0317*
X02598Y03171*
X02603Y03174*
X02606Y03179*
X02608Y03186*
X02606Y03192*
X02603Y03197*
X02598Y03201*
X02591Y03202*
X02585Y03201*
X0258Y03197*
X02576Y03192*
X02575Y03186*
X02575Y03185*
X02564Y03173*
X02559Y03176*
Y0323*
G37*
G36*
X03491Y03119D02*
X03485Y03118D01*
X0348Y03114*
X03476Y03109*
X03475Y03103*
X03476Y03096*
X0348Y03091*
X03485Y03087*
X03491Y03086*
X03498Y03087*
X03503Y03091*
X03506Y03096*
X03508Y03103*
X03506Y03109*
X03503Y03114*
X03498Y03118*
X03491Y03119*
G37*
G36*
X03717Y03088D02*
X03711Y03087D01*
X03706Y03083*
X03702Y03078*
X03701Y03072*
X03702Y03065*
X03706Y0306*
X03711Y03056*
X03717Y03055*
X03724Y03056*
X03729Y0306*
X03732Y03065*
X03734Y03072*
X03732Y03078*
X03729Y03083*
X03724Y03087*
X03717Y03088*
G37*
G36*
X03368Y03066D02*
X03362Y03065D01*
X03357Y03061*
X03353Y03056*
X03352Y0305*
X03353Y03043*
X03357Y03038*
X03362Y03034*
X03368Y03033*
X03375Y03034*
X0338Y03038*
X03383Y03043*
X03385Y0305*
X03383Y03056*
X0338Y03061*
X03375Y03065*
X03368Y03066*
G37*
G36*
X02742Y03016D02*
X02682D01*
Y0299*
X02676Y02983*
X02669*
Y03002*
X02596*
Y0294*
X0262*
Y0293*
X02618Y02927*
X02617Y02921*
X02618Y02915*
X02622Y02909*
X02627Y02906*
X02633Y02904*
X02639Y02906*
X02645Y02909*
X02648Y02915*
X02649Y02921*
X02648Y02927*
X02646Y0293*
Y0294*
X02669*
Y02959*
X02681*
X02682Y02959*
X02682Y02959*
X02742*
Y03016*
G37*
G36*
X03344Y03012D02*
X03338Y03011D01*
X03333Y03007*
X03329Y03002*
X03328Y02996*
X03329Y02989*
X03333Y02984*
X03338Y0298*
X03344Y02979*
X03351Y0298*
X03356Y02984*
X03359Y02989*
X03361Y02996*
X03359Y03002*
X03356Y03007*
X03351Y03011*
X03344Y03012*
G37*
G36*
X02473Y02996D02*
X02467Y02995D01*
X02464Y02993*
X02434*
X02429Y02992*
X02424Y02989*
X02416Y0298*
X02415*
X02414Y0298*
X02367*
Y02907*
X02428*
Y02956*
X02431Y02958*
X02439Y02966*
X02464*
X02467Y02964*
X02473Y02963*
X0248Y02964*
X02485Y02968*
X02488Y02973*
X0249Y0298*
X02488Y02986*
X02485Y02991*
X0248Y02995*
X02473Y02996*
G37*
G36*
X03197Y02986D02*
X03191Y02985D01*
X03186Y02981*
X03182Y02976*
X03181Y0297*
X03182Y02963*
X03186Y02958*
X03191Y02954*
X03197Y02953*
X03204Y02954*
X03209Y02958*
X03212Y02963*
X03214Y0297*
X03212Y02976*
X03209Y02981*
X03204Y02985*
X03197Y02986*
G37*
G36*
X03277Y02979D02*
X03271Y02978D01*
X03266Y02975*
X03262Y02969*
X03261Y02963*
X03262Y02957*
X03266Y02952*
X03271Y02948*
X03277Y02947*
X03283Y02948*
X03289Y02952*
X03292Y02957*
X03293Y02963*
X03292Y02969*
X03289Y02975*
X03283Y02978*
X03277Y02979*
G37*
G36*
X03414Y02908D02*
X03408Y02907D01*
X03403Y02903*
X03399Y02898*
X03398Y02892*
X03399Y02885*
X03403Y0288*
X03408Y02876*
X03414Y02875*
X03421Y02876*
X03426Y0288*
X03429Y02885*
X03431Y02892*
X03429Y02898*
X03426Y02903*
X03421Y02907*
X03414Y02908*
G37*
G36*
Y02752D02*
X03408Y02751D01*
X03403Y02747*
X03399Y02742*
X03398Y02736*
X03399Y02729*
X03403Y02724*
X03408Y02721*
X03414Y02719*
X03421Y02721*
X03426Y02724*
X03429Y02729*
X03431Y02736*
X03429Y02742*
X03426Y02747*
X03421Y02751*
X03414Y02752*
G37*
G36*
X03051Y02748D02*
X03044Y02747D01*
X03039Y02743*
X03036Y02738*
X03034Y02732*
X03036Y02726*
X03039Y0272*
X03044Y02717*
X03051Y02715*
X03057Y02717*
X03062Y0272*
X03066Y02726*
X03067Y02732*
X03066Y02738*
X03062Y02743*
X03057Y02747*
X03051Y02748*
G37*
G36*
X02692Y02737D02*
X02686Y02736D01*
X02681Y02732*
X02677Y02727*
X02676Y02721*
X02677Y02715*
X02681Y02709*
X02686Y02706*
X02692Y02705*
X02699Y02706*
X02704Y02709*
X02707Y02715*
X02709Y02721*
X02707Y02727*
X02704Y02732*
X02699Y02736*
X02692Y02737*
G37*
G36*
X02394Y02736D02*
X02388Y02735D01*
X02383Y02732*
X02379Y02726*
X02378Y0272*
X02379Y02714*
X02383Y02708*
X02388Y02705*
X02394Y02704*
X024Y02705*
X02406Y02708*
X02409Y02714*
X02411Y0272*
X02409Y02726*
X02406Y02732*
X024Y02735*
X02394Y02736*
G37*
G36*
X02494Y02712D02*
X02488Y02711D01*
X02483Y02707*
X02479Y02702*
X02478Y02696*
X02479Y02689*
X02483Y02684*
X02488Y02681*
X02488Y02679*
Y02678*
X02488Y02675*
X02483Y02672*
X02479Y02667*
X02478Y02661*
X02479Y02654*
X02483Y02649*
X02488Y02645*
X02494Y02644*
X02501Y02645*
X02506Y02649*
X02509Y02654*
X02511Y02661*
X02509Y02667*
X02506Y02672*
X02501Y02675*
X02501Y02678*
Y02679*
X02501Y02681*
X02506Y02684*
X02509Y02689*
X02511Y02696*
X02509Y02702*
X02506Y02707*
X02501Y02711*
X02494Y02712*
G37*
G36*
X02279Y0263D02*
X02273Y02629D01*
X02268Y02625*
X02262Y02626*
X02258Y02628*
X02252Y02629*
X02246Y02628*
X0224Y02625*
X02237Y02619*
X02236Y02613*
X02237Y02607*
X0224Y02602*
X02246Y02598*
X02252Y02597*
X02258Y02598*
X02263Y02602*
X02269Y02601*
X02273Y02599*
X02279Y02597*
X02286Y02599*
X02291Y02602*
X02294Y02607*
X02296Y02614*
X02294Y0262*
X02291Y02625*
X02286Y02629*
X02279Y0263*
G37*
G36*
X02958Y02637D02*
X02952Y02636D01*
X02947Y02632*
X02943Y02627*
X02942Y02621*
X02943Y02614*
X02947Y02609*
X02952Y02605*
X02958Y02604*
X02965Y02605*
X0297Y02609*
X02973Y02614*
X02975Y02621*
X02973Y02627*
X0297Y02632*
X02965Y02636*
X02958Y02637*
G37*
G36*
X02429D02*
X02422Y02636D01*
X02417Y02632*
X02414Y02627*
X02412Y02621*
X02414Y02614*
X02417Y02609*
X02422Y02605*
X02429Y02604*
X02435Y02605*
X0244Y02609*
X02444Y02614*
X02445Y02621*
X02444Y02627*
X0244Y02632*
X02435Y02636*
X02429Y02637*
G37*
G36*
X02385Y0263D02*
X02379Y02628D01*
X02374Y02625*
X0237Y0262*
X02369Y02613*
X0237Y02607*
X02374Y02602*
X02379Y02598*
X02385Y02597*
X02392Y02598*
X02397Y02602*
X024Y02607*
X02402Y02613*
X024Y0262*
X02397Y02625*
X02392Y02628*
X02385Y0263*
G37*
G36*
X02821Y02617D02*
X02815Y02616D01*
X0281Y02612*
X02806Y02607*
X02805Y02601*
X02806Y02594*
X0281Y02589*
X02815Y02585*
X02821Y02584*
X02828Y02585*
X02833Y02589*
X02836Y02594*
X02838Y02601*
X02836Y02607*
X02833Y02612*
X02828Y02616*
X02821Y02617*
G37*
G36*
X02779D02*
X02773Y02616D01*
X02767Y02612*
X02764Y02607*
X02763Y02601*
X02764Y02594*
X02767Y02589*
X02773Y02585*
X02779Y02584*
X02785Y02585*
X02791Y02589*
X02794Y02594*
X02795Y02601*
X02794Y02607*
X02791Y02612*
X02785Y02616*
X02779Y02617*
G37*
G36*
X02688D02*
X02682Y02616D01*
X02677Y02612*
X02673Y02607*
X02672Y02601*
X02673Y02594*
X02677Y02589*
X02682Y02585*
X02688Y02584*
X02695Y02585*
X027Y02589*
X02704Y02594*
X02705Y02601*
X02704Y02607*
X027Y02612*
X02695Y02616*
X02688Y02617*
G37*
G36*
X0259D02*
X02584Y02616D01*
X02579Y02612*
X02575Y02607*
X02574Y02601*
X02575Y02594*
X02579Y02589*
X02584Y02585*
X0259Y02584*
X02596Y02585*
X02602Y02589*
X02605Y02594*
X02606Y02601*
X02605Y02607*
X02602Y02612*
X02596Y02616*
X0259Y02617*
G37*
G36*
X03623Y02603D02*
X03617Y02602D01*
X03612Y02598*
X03608Y02593*
X03607Y02587*
X03608Y0258*
X03612Y02575*
X03617Y02571*
X03623Y0257*
X0363Y02571*
X03635Y02575*
X03638Y0258*
X0364Y02587*
X03638Y02593*
X03635Y02598*
X0363Y02602*
X03623Y02603*
G37*
G36*
X02488Y02591D02*
X02481Y02589D01*
X02476Y02586*
X02473Y02581*
X02471Y02574*
X02473Y02568*
X02476Y02563*
X02481Y02559*
X02488Y02558*
X02494Y02559*
X02499Y02563*
X02503Y02568*
X02504Y02574*
X02503Y02581*
X02499Y02586*
X02494Y02589*
X02488Y02591*
G37*
G36*
X02881Y02582D02*
X02875Y02581D01*
X0287Y02577*
X02866Y02572*
X02865Y02566*
X02866Y02559*
X0287Y02554*
X02875Y0255*
X02881Y02549*
X02888Y0255*
X02893Y02554*
X02896Y02559*
X02898Y02566*
X02896Y02572*
X02893Y02577*
X02888Y02581*
X02881Y02582*
G37*
G36*
X02624Y02477D02*
X02618Y02476D01*
X02613Y02472*
X02609Y02467*
X02608Y02461*
X02609Y02454*
X02609Y02454*
X02606Y0245*
X02606Y02451*
X02599Y02452*
X02593Y02451*
X02588Y02447*
X02584Y02442*
X02583Y02436*
X02584Y02431*
X02583Y0243*
X02581Y02427*
X0258Y02427*
X02575Y02428*
X02569Y02427*
X02564Y02423*
X0256Y02418*
X02559Y02412*
X0256Y02405*
X02564Y024*
X02569Y02396*
X02575Y02395*
X02582Y02396*
X02587Y024*
X0259Y02405*
X02592Y02412*
X02591Y02416*
X02591Y02417*
X02594Y0242*
X02595Y0242*
X02599Y02419*
X02606Y0242*
X02611Y02424*
X02614Y02429*
X02616Y02436*
X02614Y02442*
X02614Y02442*
X02618Y02446*
X02618Y02445*
X02624Y02444*
X02631Y02445*
X02636Y02449*
X02639Y02454*
X02641Y02461*
X02639Y02467*
X02636Y02472*
X02631Y02476*
X02624Y02477*
G37*
G36*
X02272Y0248D02*
X02265Y02478D01*
X0226Y02475*
X02256Y0247*
X02255Y02463*
X02256Y02457*
X0226Y02452*
X02265Y02448*
X02272Y02447*
X02278Y02448*
X02283Y02452*
X02287Y02457*
X02288Y02463*
X02287Y0247*
X02283Y02475*
X02278Y02478*
X02272Y0248*
G37*
G36*
X02525Y02479D02*
X02519Y02478D01*
X02514Y02474*
X0251Y02469*
X02509Y02463*
X0251Y02456*
X02514Y02451*
X02519Y02447*
X02525Y02446*
X02532Y02447*
X02537Y02451*
X0254Y02456*
X02542Y02463*
X0254Y02469*
X02537Y02474*
X02532Y02478*
X02525Y02479*
G37*
G36*
X02948Y02472D02*
X02942Y02471D01*
X02936Y02468*
X02933Y02462*
X02931Y02456*
X02933Y0245*
X02936Y02444*
X02942Y02441*
X02948Y0244*
X02954Y02441*
X02959Y02444*
X02963Y0245*
X02964Y02456*
X02963Y02462*
X02959Y02468*
X02954Y02471*
X02948Y02472*
G37*
G36*
X0299Y02456D02*
X02982Y02455D01*
X02976Y02451*
X02972Y02444*
X0297Y02437*
X02972Y0243*
X02976Y02424*
X02982Y02419*
X0299Y02418*
X02997Y02419*
X03003Y02424*
X03007Y0243*
X03009Y02437*
X03007Y02444*
X03003Y02451*
X02997Y02455*
X0299Y02456*
G37*
G36*
X02202D02*
X02195Y02455D01*
X02189Y02451*
X02185Y02444*
X02183Y02437*
X02185Y0243*
X02189Y02424*
X02195Y02419*
X02202Y02418*
X0221Y02419*
X02216Y02424*
X0222Y0243*
X02221Y02437*
X0222Y02444*
X02216Y02451*
X0221Y02455*
X02202Y02456*
G37*
G36*
X03617Y02552D02*
X03604Y02551D01*
X03591Y02547*
X0358Y02541*
X03569Y02533*
X03561Y02522*
X03555Y02511*
X03551Y02498*
X0355Y02485*
X03551Y02472*
X03555Y02459*
X03561Y02447*
X03569Y02437*
X0358Y02429*
X03591Y02423*
X03604Y02419*
X03617Y02417*
X0363Y02419*
X03643Y02423*
X03654Y02429*
X03665Y02437*
X03673Y02447*
X03679Y02459*
X03683Y02472*
X03684Y02485*
X03683Y02498*
X03679Y02511*
X03673Y02522*
X03665Y02533*
X03654Y02541*
X03643Y02547*
X0363Y02551*
X03617Y02552*
G37*
G36*
X02783Y02449D02*
X02777Y02448D01*
X02771Y02444*
X02768Y02439*
X02767Y02433*
X02768Y02426*
X02771Y02421*
X02777Y02418*
X02783Y02416*
X02789Y02418*
X02795Y02421*
X02798Y02426*
X02799Y02433*
X02798Y02439*
X02795Y02444*
X02789Y02448*
X02783Y02449*
G37*
G36*
X02484Y02445D02*
X02478Y02444D01*
X02472Y0244*
X02469Y02435*
X02467Y02429*
X02469Y02422*
X02472Y02417*
X02478Y02414*
X02484Y02412*
X0249Y02414*
X02495Y02417*
X02499Y02422*
X025Y02429*
X02499Y02435*
X02495Y0244*
X0249Y02444*
X02484Y02445*
G37*
G36*
X02421D02*
X02415Y02444D01*
X02409Y0244*
X02406Y02435*
X02404Y02429*
X02406Y02422*
X02409Y02417*
X02415Y02414*
X02421Y02412*
X02427Y02414*
X02432Y02417*
X02436Y02422*
X02437Y02429*
X02436Y02435*
X02432Y0244*
X02427Y02444*
X02421Y02445*
G37*
G36*
X02322D02*
X02316Y02444D01*
X02311Y0244*
X02307Y02435*
X02306Y02429*
X02307Y02422*
X02311Y02417*
X02316Y02414*
X02322Y02412*
X02329Y02414*
X02334Y02417*
X02337Y02422*
X02339Y02429*
X02337Y02435*
X02334Y0244*
X02329Y02444*
X02322Y02445*
G37*
G36*
X02894Y02447D02*
X02888Y02446D01*
X02883Y02442*
X02879Y02437*
X02878Y02431*
X02879Y02424*
X02883Y02419*
X02888Y02415*
X02894Y02414*
X02901Y02415*
X02906Y02419*
X02907*
X02909Y02416*
X02914Y02412*
X0292Y02411*
X02927Y02412*
X02932Y02416*
X02935Y02421*
X02937Y02428*
X02935Y02434*
X02932Y02439*
X02927Y02443*
X0292Y02444*
X02914Y02443*
X02909Y02439*
X02908*
X02906Y02442*
X02901Y02446*
X02894Y02447*
G37*
G36*
X03498Y02357D02*
X03492Y02356D01*
X03487Y02352*
X03483Y02347*
X03482Y02341*
X03483Y02334*
X03487Y02329*
X03492Y02325*
X03498Y02324*
X03505Y02325*
X0351Y02329*
X03513Y02334*
X03515Y02341*
X03513Y02347*
X0351Y02352*
X03505Y02356*
X03498Y02357*
G37*
G36*
X02475Y02307D02*
X02469Y02306D01*
X02464Y02302*
X02462Y02299*
X02457Y02297*
X02455Y02297*
X0245Y02298*
X02444Y02297*
X02439Y02293*
X02435Y02288*
X02434Y02282*
X02435Y02275*
X02439Y0227*
X02444Y02266*
X0245Y02265*
X02457Y02266*
X02462Y0227*
X02465Y02275*
X0247Y02275*
X02475Y02274*
X02482Y02275*
X02487Y02279*
X0249Y02284*
X02492Y02291*
X0249Y02297*
X02487Y02302*
X02482Y02306*
X02475Y02307*
G37*
G36*
X02803Y02323D02*
X02797Y02322D01*
X02792Y02318*
X02788Y02313*
X02787Y02307*
X02788Y023*
X02792Y02295*
X02797Y02291*
X02803Y0229*
X0281Y02291*
X02815Y02295*
X02818Y023*
X0282Y02307*
X02818Y02313*
X02815Y02318*
X0281Y02322*
X02803Y02323*
G37*
G36*
X02685Y02327D02*
X02679Y02326D01*
X02674Y02322*
X0267Y02317*
X02669Y02311*
X0267Y02307*
X02664Y02306*
X02659Y02302*
X02656Y02297*
X02654Y02291*
X02655Y02289*
X02654Y02288*
X0265Y02285*
X02645Y02286*
X02639Y02285*
X02634Y02281*
X0263Y02276*
X02629Y0227*
X0263Y02264*
X02634Y02258*
X02639Y02255*
X02645Y02254*
X02652Y02255*
X02657Y02258*
X0266Y02264*
X02662Y0227*
X02661Y02272*
X02662Y02273*
X02666Y02275*
X02671Y02274*
X02677Y02275*
X02682Y02279*
X02683Y0228*
X02689Y0228*
X02691Y02277*
X02696Y02273*
X02702Y02272*
X02709Y02273*
X02714Y02277*
X02716Y0228*
X0272Y02277*
X02726Y02276*
X02733Y02277*
X02738Y02281*
X02741Y02286*
X02743Y02293*
X02741Y02299*
X02738Y02304*
X02733Y02308*
X02726Y02309*
X0272Y02308*
X02715Y02304*
X02713Y02301*
X02709Y02304*
X02706Y02304*
X02701Y02309*
X02702Y02311*
X027Y02317*
X02697Y02322*
X02692Y02326*
X02685Y02327*
G37*
G36*
X02618Y02315D02*
X02611Y02314D01*
X02606Y0231*
X02603Y02305*
X02601Y02299*
X02603Y02292*
X02606Y02287*
X02611Y02284*
X02618Y02282*
X02624Y02284*
X02629Y02287*
X02633Y02292*
X02634Y02299*
X02633Y02305*
X02629Y0231*
X02624Y02314*
X02618Y02315*
G37*
G36*
X02874Y02306D02*
X02867Y02305D01*
X02862Y02302*
X02858Y02296*
X02857Y0229*
X02858Y02284*
X02862Y02279*
X02867Y02275*
X02874Y02274*
X0288Y02275*
X02885Y02279*
X02889Y02284*
X0289Y0229*
X02889Y02296*
X02885Y02302*
X0288Y02305*
X02874Y02306*
G37*
G36*
X02985Y02303D02*
X02979Y02302D01*
X02974Y02298*
X0297Y02293*
X02969Y02287*
X0297Y0228*
X02974Y02275*
X02979Y02271*
X02985Y0227*
X02992Y02271*
X02997Y02275*
X03Y0228*
X03002Y02287*
X03Y02293*
X02997Y02298*
X02992Y02302*
X02985Y02303*
G37*
G36*
X02942Y02302D02*
X02936Y02301D01*
X02931Y02297*
X02927Y02292*
X02926Y02286*
X02927Y02279*
X02931Y02274*
X02936Y0227*
X02942Y02269*
X02949Y0227*
X02954Y02274*
X02957Y02279*
X02959Y02286*
X02957Y02292*
X02954Y02297*
X02949Y02301*
X02942Y02302*
G37*
G36*
X02409Y0233D02*
X02403Y02329D01*
X02398Y02325*
X02394Y0232*
X02393Y02314*
X02394Y02307*
X02398Y02302*
X02399Y02301*
Y02295*
X02398Y02294*
X02394Y02289*
X02393Y02283*
X02394Y02276*
X02398Y02271*
X02403Y02267*
X02409Y02266*
X02416Y02267*
X02421Y02271*
X02424Y02276*
X02426Y02283*
X02424Y02289*
X02421Y02294*
X02419Y02295*
Y02301*
X02421Y02302*
X02424Y02307*
X02426Y02314*
X02424Y0232*
X02421Y02325*
X02416Y02329*
X02409Y0233*
G37*
G36*
X02579Y02297D02*
X02573Y02296D01*
X02568Y02292*
X02564Y02287*
X02563Y02281*
X02564Y02274*
X02568Y02269*
X02573Y02265*
X02579Y02264*
X02586Y02265*
X02591Y02269*
X02594Y02274*
X02596Y02281*
X02594Y02287*
X02591Y02292*
X02586Y02296*
X02579Y02297*
G37*
G36*
X03342Y02279D02*
X03336Y02278D01*
X03331Y02274*
X03327Y02269*
X03326Y02263*
X03327Y02256*
X03331Y02251*
X03336Y02247*
X03342Y02246*
X03349Y02247*
X03354Y02251*
X03357Y02256*
X03359Y02263*
X03357Y02269*
X03354Y02274*
X03349Y02278*
X03342Y02279*
G37*
G36*
X02841D02*
X02835Y02278D01*
X0283Y02274*
X02826Y02269*
X02825Y02263*
X02826Y02256*
X0283Y02251*
X02835Y02247*
X02841Y02246*
X02848Y02247*
X02853Y02251*
X02856Y02256*
X02858Y02263*
X02856Y02269*
X02853Y02274*
X02848Y02278*
X02841Y02279*
G37*
G36*
X02499Y02252D02*
X02493Y02251D01*
X02488Y02247*
X02484Y02242*
X02483Y02236*
X02484Y02229*
X02488Y02224*
X02493Y0222*
X02499Y02219*
X02506Y0222*
X02511Y02224*
X02514Y02229*
X02516Y02236*
X02514Y02242*
X02511Y02247*
X02506Y02251*
X02499Y02252*
G37*
G36*
X0233Y02231D02*
X02324Y0223D01*
X02319Y02226*
X02315Y02221*
X02314Y02215*
X02315Y02208*
X02319Y02203*
X02324Y02199*
X0233Y02198*
X02337Y02199*
X02342Y02203*
X02345Y02208*
X02347Y02215*
X02345Y02221*
X02342Y02226*
X02337Y0223*
X0233Y02231*
G37*
G36*
X03571Y02115D02*
X03564Y02114D01*
X03557Y02109*
X03553Y02103*
X03552Y02096*
X03553Y02088*
X03557Y02082*
X03564Y02078*
X03571Y02077*
X03578Y02078*
X03584Y02082*
X03589Y02088*
X0359Y02096*
X03589Y02103*
X03584Y02109*
X03578Y02114*
X03571Y02115*
G37*
G36*
X03719Y02012D02*
X03713Y02011D01*
X03708Y02007*
X03704Y02002*
X03703Y01996*
X03704Y01989*
X03708Y01984*
X03713Y0198*
X03719Y01979*
X03726Y0198*
X03731Y01984*
X03734Y01989*
X03736Y01996*
X03734Y02002*
X03731Y02007*
X03726Y02011*
X03719Y02012*
G37*
G36*
X03554Y02007D02*
X03548Y02006D01*
X03543Y02002*
X03539Y01997*
X03538Y01991*
X03539Y01984*
X03543Y01979*
X03548Y01975*
X03554Y01974*
X03561Y01975*
X03566Y01979*
X03569Y01984*
X03571Y01991*
X03569Y01997*
X03566Y02002*
X03561Y02006*
X03554Y02007*
G37*
G36*
X03298Y01987D02*
X03292Y01986D01*
X03287Y01982*
X03283Y01977*
X03282Y01971*
X03283Y01964*
X03287Y01959*
X03292Y01955*
X03298Y01954*
X03305Y01955*
X0331Y01959*
X03313Y01964*
X03315Y01971*
X03313Y01977*
X0331Y01982*
X03305Y01986*
X03298Y01987*
G37*
G36*
X03554Y01957D02*
X03548Y01956D01*
X03543Y01952*
X03539Y01947*
X03538Y01941*
X03539Y01934*
X03543Y01929*
X03548Y01925*
X03554Y01924*
X03561Y01925*
X03566Y01929*
X03569Y01934*
X03571Y01941*
X03569Y01947*
X03566Y01952*
X03561Y01956*
X03554Y01957*
G37*
G36*
X03719Y01937D02*
X03713Y01936D01*
X03708Y01932*
X03704Y01927*
X03703Y01921*
X03704Y01914*
X03708Y01909*
X03713Y01905*
X03719Y01904*
X03726Y01905*
X03731Y01909*
X03734Y01914*
X03736Y01921*
X03734Y01927*
X03731Y01932*
X03726Y01936*
X03719Y01937*
G37*
G36*
X03554Y01907D02*
X03548Y01906D01*
X03543Y01902*
X03539Y01897*
X03538Y01891*
X03539Y01884*
X03543Y01879*
X03548Y01875*
X03554Y01874*
X03561Y01875*
X03566Y01879*
X03569Y01884*
X03571Y01891*
X03569Y01897*
X03566Y01902*
X03561Y01906*
X03554Y01907*
G37*
G36*
X03392Y01887D02*
X03386Y01886D01*
X03381Y01882*
X03377Y01877*
X03376Y01871*
X03377Y01864*
X03381Y01859*
X03386Y01855*
X03392Y01854*
X03399Y01855*
X03404Y01859*
X03407Y01864*
X03409Y01871*
X03407Y01877*
X03404Y01882*
X03399Y01886*
X03392Y01887*
G37*
G36*
X03439Y01887D02*
X03433Y01886D01*
X03427Y01882*
X03424Y01877*
X03422Y0187*
X03424Y01864*
X03427Y01859*
X03433Y01855*
X03439Y01854*
X03445Y01855*
X0345Y01859*
X03454Y01864*
X03455Y0187*
X03454Y01877*
X0345Y01882*
X03445Y01886*
X03439Y01887*
G37*
G36*
X03554Y01857D02*
X03548Y01856D01*
X03543Y01852*
X03539Y01847*
X03538Y01841*
X03539Y01834*
X03543Y01829*
X03548Y01825*
X03554Y01824*
X03561Y01825*
X03566Y01829*
X03569Y01834*
X03571Y01841*
X03569Y01847*
X03566Y01852*
X03561Y01856*
X03554Y01857*
G37*
G36*
X03804Y01856D02*
X03798Y01855D01*
X03793Y01851*
X03789Y01846*
X03788Y0184*
X03789Y01833*
X03793Y01828*
X03798Y01824*
X03804Y01823*
X03811Y01824*
X03816Y01828*
X03819Y01833*
X03821Y0184*
X03819Y01846*
X03816Y01851*
X03811Y01855*
X03804Y01856*
G37*
G36*
X06694Y01847D02*
X06688Y01845D01*
X06683Y01842*
X06679Y01837*
X06678Y0183*
X06679Y01824*
X06683Y01819*
X06688Y01815*
X06694Y01814*
X06701Y01815*
X06706Y01819*
X06709Y01824*
X06711Y0183*
X06709Y01837*
X06706Y01842*
X06701Y01845*
X06694Y01847*
G37*
G36*
X03329Y01842D02*
X03322Y01841D01*
X03317Y01837*
X03314Y01832*
X03312Y01826*
X03314Y01819*
X03317Y01814*
X03322Y0181*
X03329Y01809*
X03335Y0181*
X0334Y01814*
X03344Y01819*
X03345Y01826*
X03344Y01832*
X0334Y01837*
X03335Y01841*
X03329Y01842*
G37*
G36*
X03944Y01832D02*
X03938Y01831D01*
X03933Y01827*
X03929Y01822*
X03928Y01816*
X03929Y01809*
X03933Y01804*
X03938Y018*
X03944Y01799*
X03951Y018*
X03956Y01804*
X03959Y01809*
X03961Y01816*
X03959Y01822*
X03956Y01827*
X03951Y01831*
X03944Y01832*
G37*
G36*
X03056Y01828D02*
X0305Y01826D01*
X03045Y01823*
X03041Y01818*
X0304Y01811*
X03041Y01805*
X03045Y018*
X0305Y01796*
X03056Y01795*
X03063Y01796*
X03068Y018*
X03071Y01805*
X03073Y01811*
X03071Y01818*
X03068Y01823*
X03063Y01826*
X03056Y01828*
G37*
G36*
X03414Y01821D02*
X03408Y0182D01*
X03402Y01816*
X03399Y01811*
X03398Y01805*
X03399Y01798*
X03402Y01793*
X03408Y01789*
X03414Y01788*
X0342Y01789*
X03426Y01793*
X03429Y01798*
X0343Y01805*
X03429Y01811*
X03426Y01816*
X0342Y0182*
X03414Y01821*
G37*
G36*
X04064Y01812D02*
X04058Y01811D01*
X04053Y01807*
X04049Y01802*
X04048Y01796*
X04049Y01789*
X04053Y01784*
X04058Y0178*
X04064Y01779*
X04071Y0178*
X04076Y01784*
X04079Y01789*
X04081Y01796*
X04079Y01802*
X04076Y01807*
X04071Y01811*
X04064Y01812*
G37*
G36*
X06594Y01791D02*
X06588Y0179D01*
X06582Y01787*
X06579Y01781*
X06578Y01775*
X06579Y01769*
X06582Y01764*
X06588Y0176*
X06594Y01759*
X066Y0176*
X06606Y01764*
X06609Y01769*
X0661Y01775*
X06609Y01781*
X06606Y01787*
X066Y0179*
X06594Y01791*
G37*
G36*
X03719Y01782D02*
X03713Y01781D01*
X03708Y01777*
X03704Y01772*
X03703Y01766*
X03704Y01759*
X03708Y01754*
X03713Y0175*
X03719Y01749*
X03726Y0175*
X03731Y01754*
X03734Y01759*
X03736Y01766*
X03734Y01772*
X03731Y01777*
X03726Y01781*
X03719Y01782*
G37*
G36*
X04134Y01767D02*
X04128Y01766D01*
X04123Y01762*
X04119Y01757*
X04118Y01751*
X04119Y01744*
X04123Y01739*
X04128Y01735*
X04134Y01734*
X04141Y01735*
X04146Y01739*
X04149Y01744*
X04151Y01751*
X04149Y01757*
X04146Y01762*
X04141Y01766*
X04134Y01767*
G37*
G36*
X06594Y01736D02*
X06588Y01735D01*
X06582Y01732*
X06579Y01726*
X06578Y0172*
X06579Y01714*
X06582Y01708*
X06588Y01705*
X06594Y01704*
X066Y01705*
X06606Y01708*
X06609Y01714*
X0661Y0172*
X06609Y01726*
X06606Y01732*
X066Y01735*
X06594Y01736*
G37*
G36*
X03197Y0173D02*
X03191Y01729D01*
X03185Y01725*
X03182Y0172*
X0318Y01714*
X03182Y01707*
X03185Y01702*
X03191Y01698*
X03197Y01697*
X03203Y01698*
X03208Y01702*
X03212Y01707*
X03213Y01714*
X03212Y0172*
X03208Y01725*
X03203Y01729*
X03197Y0173*
G37*
G36*
X0341Y01729D02*
X03404Y01728D01*
X03399Y01725*
X03395Y01719*
X03394Y01713*
X03395Y01707*
X03399Y01702*
X03404Y01698*
X0341Y01697*
X03417Y01698*
X03422Y01702*
X03425Y01707*
X03427Y01713*
X03425Y01719*
X03422Y01725*
X03417Y01728*
X0341Y01729*
G37*
G36*
X03718Y01729D02*
X03712Y01728D01*
X03707Y01724*
X03703Y01719*
X03702Y01713*
X03703Y01706*
X03707Y01701*
X03712Y01698*
X03718Y01696*
X03725Y01698*
X0373Y01701*
X03733Y01706*
X03735Y01713*
X03733Y01719*
X0373Y01724*
X03725Y01728*
X03718Y01729*
G37*
G36*
X03996Y01727D02*
X0399Y01726D01*
X03985Y01722*
X03981Y01717*
X0398Y01711*
X03981Y01704*
X03985Y01699*
X0399Y01695*
X03996Y01694*
X04003Y01695*
X04008Y01699*
X04011Y01704*
X04013Y01711*
X04011Y01717*
X04008Y01722*
X04003Y01726*
X03996Y01727*
G37*
G36*
X03589D02*
X03583Y01726D01*
X03578Y01722*
X03574Y01717*
X03573Y01711*
X03574Y01704*
X03578Y01699*
X03583Y01695*
X03589Y01694*
X03596Y01695*
X03601Y01699*
X03604Y01704*
X03606Y01711*
X03604Y01717*
X03601Y01722*
X03596Y01726*
X03589Y01727*
G37*
G36*
X03747Y01696D02*
X03741Y01695D01*
X03736Y01691*
X03732Y01686*
X03731Y01682*
X03726Y01681*
X03724Y01684*
X03718Y01688*
X03712Y01689*
X03706Y01688*
X03701Y01684*
X03697Y01679*
X03696Y01673*
X03697Y01666*
X03701Y01661*
X03706Y01658*
X03712Y01656*
X03718Y01658*
X03724Y01661*
X03727Y01666*
X03728Y0167*
X03733Y01671*
X03736Y01668*
X03741Y01664*
X03747Y01663*
X03753Y01664*
X03758Y01661*
X03758Y01659*
X03762Y01654*
X03767Y01651*
X03773Y01649*
X0378Y01651*
X03785Y01654*
X03788Y01659*
X0379Y01666*
X03788Y01672*
X03785Y01677*
X0378Y01681*
X03773Y01682*
X03767Y01681*
X03763Y01684*
X03762Y01686*
X03759Y01691*
X03753Y01695*
X03747Y01696*
G37*
G36*
X03803Y01707D02*
X03797Y01706D01*
X03792Y01702*
X03788Y01697*
X03787Y01691*
X03788Y01684*
X03792Y01679*
X03797Y01675*
X03803Y01674*
X0381Y01675*
X03815Y01679*
X03818Y01684*
X0382Y01691*
X03818Y01697*
X03815Y01702*
X0381Y01706*
X03803Y01707*
G37*
G36*
X06594Y01689D02*
X06588Y01688D01*
X06582Y01684*
X06579Y01679*
X06578Y01673*
X06579Y01666*
X06582Y01661*
X06588Y01658*
X06594Y01656*
X066Y01658*
X06606Y01661*
X06609Y01666*
X0661Y01673*
X06609Y01679*
X06606Y01684*
X066Y01688*
X06594Y01689*
G37*
G36*
X03968Y01687D02*
X03962Y01686D01*
X03957Y01682*
X03953Y01677*
X03952Y01671*
X03953Y01664*
X03957Y01659*
X03962Y01655*
X03968Y01654*
X03975Y01655*
X0398Y01659*
X03983Y01664*
X03985Y01671*
X03983Y01677*
X0398Y01682*
X03975Y01686*
X03968Y01687*
G37*
G36*
X0359Y01678D02*
X03584Y01677D01*
X03579Y01673*
X03575Y01668*
X03574Y01662*
X03575Y01655*
X03579Y0165*
X03584Y01646*
X0359Y01645*
X03597Y01646*
X03602Y0165*
X03605Y01655*
X03607Y01662*
X03605Y01668*
X03602Y01673*
X03597Y01677*
X0359Y01678*
G37*
G36*
X03224Y01677D02*
X03218Y01676D01*
X03213Y01672*
X03209Y01667*
X03208Y01661*
X03209Y01655*
X03213Y01649*
X03218Y01646*
X03224Y01645*
X03231Y01646*
X03235Y01649*
X03239Y01649*
X03241Y01649*
X03246Y01645*
X03252Y01644*
X03259Y01645*
X03264Y01649*
X03267Y01654*
X03269Y01661*
X03267Y01667*
X03264Y01672*
X03259Y01676*
X03252Y01677*
X03246Y01676*
X03242Y01673*
X03238Y01672*
X03235Y01673*
X03231Y01676*
X03224Y01677*
G37*
G36*
X05578Y01735D02*
X05566Y01734D01*
X05555Y01729*
X05545Y01722*
X05538Y01712*
X05533Y01701*
X05532Y01689*
X05533Y01677*
X05538Y01666*
X05545Y01657*
X05555Y0165*
X05566Y01645*
X05578Y01643*
X0559Y01645*
X05601Y0165*
X0561Y01657*
X05617Y01666*
X05622Y01677*
X05624Y01689*
X05622Y01701*
X05617Y01712*
X0561Y01722*
X05601Y01729*
X0559Y01734*
X05578Y01735*
G37*
G36*
X06594Y01626D02*
X06588Y01625D01*
X06582Y01621*
X06579Y01616*
X06578Y0161*
X06579Y01603*
X06582Y01598*
X06588Y01595*
X06594Y01593*
X066Y01595*
X06606Y01598*
X06609Y01603*
X0661Y0161*
X06609Y01616*
X06606Y01621*
X066Y01625*
X06594Y01626*
G37*
G36*
X04131Y01702D02*
X04125Y01701D01*
X0412Y01697*
X04116Y01692*
X04115Y01686*
X04116Y01679*
X0412Y01674*
X04125Y0167*
X04127Y0167*
X04127Y01669*
X04127Y01665*
X04123Y01662*
X04119Y01657*
X04118Y01651*
X04119Y01644*
X04123Y01639*
X04128Y01635*
X04133Y01634*
X04135Y01631*
X04136Y01629*
X04136Y01629*
X04134Y01623*
X04136Y01617*
X04139Y01612*
X04145Y01608*
X04151Y01607*
X04157Y01608*
X04161Y01611*
X04164Y01607*
X04164Y01607*
X04163Y01601*
X04164Y01594*
X04168Y01589*
X04173Y01585*
X04179Y01584*
X04186Y01585*
X04191Y01589*
X04194Y01594*
X04196Y01601*
X04194Y01607*
X04191Y01612*
X04186Y01616*
X04179Y01617*
X04173Y01616*
X04169Y01613*
X04166Y01617*
X04166Y01617*
X04167Y01623*
X04166Y01629*
X04162Y01635*
X04157Y01638*
X04152Y01639*
X0415Y01643*
X04149Y01644*
X04149Y01644*
X04151Y01651*
X04149Y01657*
X04146Y01662*
X04141Y01666*
X04139Y01666*
X04139Y01667*
X04139Y01671*
X04143Y01674*
X04146Y01679*
X04148Y01686*
X04146Y01692*
X04143Y01697*
X04138Y01701*
X04131Y01702*
G37*
G36*
X03413Y01589D02*
X03407Y01588D01*
X03402Y01584*
X03398Y01579*
X03397Y01573*
X03398Y01566*
X03402Y01561*
X03407Y01557*
X03413Y01556*
X0342Y01557*
X03425Y01561*
X03428Y01566*
X0343Y01573*
X03428Y01579*
X03425Y01584*
X0342Y01588*
X03413Y01589*
G37*
G36*
X03894Y01582D02*
X03888Y01581D01*
X03883Y01577*
X03879Y01572*
X03878Y01566*
X03879Y01559*
X03883Y01554*
X03888Y0155*
X03894Y01549*
X03901Y0155*
X03906Y01554*
X03909Y01559*
X03911Y01566*
X03909Y01572*
X03906Y01577*
X03901Y01581*
X03894Y01582*
G37*
G36*
X03969Y01568D02*
X03963Y01567D01*
X03958Y01563*
X03954Y01558*
X03953Y01552*
X03954Y01545*
X03958Y0154*
X03963Y01536*
X03969Y01535*
X03976Y01536*
X03978Y01538*
X03983Y01539*
X03985Y01537*
X03988Y01535*
X03994Y01534*
X04001Y01535*
X04006Y01539*
X04009Y01544*
X04011Y01551*
X04009Y01557*
X04006Y01562*
X04001Y01566*
X03994Y01567*
X03988Y01566*
X03983Y01562*
X03982*
X03981Y01563*
X03976Y01567*
X03969Y01568*
G37*
G36*
X04034Y01562D02*
X04028Y01561D01*
X04023Y01557*
X04019Y01552*
X04018Y01546*
X04019Y01539*
X04023Y01534*
X04028Y0153*
X04034Y01529*
X04041Y0153*
X04046Y01534*
X04049Y01539*
X04051Y01546*
X04049Y01552*
X04046Y01557*
X04041Y01561*
X04034Y01562*
G37*
G36*
X03924Y01552D02*
X03918Y01551D01*
X03913Y01547*
X03909Y01542*
X03908Y01536*
X03909Y01529*
X03913Y01524*
X03918Y0152*
X03924Y01519*
X03931Y0152*
X03936Y01524*
X03939Y01529*
X03941Y01536*
X03939Y01542*
X03936Y01547*
X03931Y01551*
X03924Y01552*
G37*
G36*
X02894Y01577D02*
X02888Y01576D01*
X02883Y01572*
X02879Y01567*
X02878Y01561*
X02879Y01554*
X02883Y01549*
X02888Y01545*
X02894Y01544*
X02901Y01545*
X02901Y01546*
X02904Y01542*
X02904Y01542*
X02903Y01536*
X02904Y01529*
X02908Y01524*
X02913Y0152*
X02919Y01519*
X02926Y0152*
X02931Y01524*
X02934Y01529*
X02936Y01536*
X02934Y01542*
X02931Y01547*
X02926Y01551*
X02919Y01552*
X02913Y01551*
X02913Y0155*
X02909Y01554*
X02909Y01554*
X02911Y01561*
X02909Y01567*
X02906Y01572*
X02901Y01576*
X02894Y01577*
G37*
G36*
X06587Y01545D02*
X06581Y01544D01*
X06576Y0154*
X06572Y01535*
X06571Y01529*
X06572Y01523*
X06576Y01517*
X06581Y01514*
X06587Y01513*
X06594Y01514*
X06599Y01517*
X06602Y01523*
X06604Y01529*
X06602Y01535*
X06599Y0154*
X06594Y01544*
X06587Y01545*
G37*
G36*
X03594Y0153D02*
X03588Y01529D01*
X03583Y01525*
X03579Y0152*
X03578Y01514*
X03579Y01507*
X03583Y01502*
X03588Y01498*
X03594Y01497*
X03601Y01498*
X03606Y01502*
X03609Y01507*
X03611Y01514*
X03609Y0152*
X03606Y01525*
X03601Y01529*
X03594Y0153*
G37*
G36*
X04064Y01527D02*
X04058Y01526D01*
X04053Y01522*
X04049Y01517*
X04048Y01511*
X04049Y01504*
X04053Y01499*
X04058Y01495*
X04064Y01494*
X04071Y01495*
X04076Y01499*
X04079Y01504*
X04081Y01511*
X04079Y01517*
X04076Y01522*
X04071Y01526*
X04064Y01527*
G37*
G36*
X03864D02*
X03858Y01526D01*
X03853Y01522*
X03849Y01517*
X03848Y01511*
X03849Y01504*
X03853Y01499*
X03858Y01495*
X03864Y01494*
X03871Y01495*
X03876Y01499*
X03879Y01504*
X03881Y01511*
X03879Y01517*
X03876Y01522*
X03871Y01526*
X03864Y01527*
G37*
G36*
X03834Y01497D02*
X03828Y01496D01*
X03823Y01492*
X03819Y01487*
X03818Y01481*
X03819Y01474*
X03823Y01469*
X03828Y01465*
X03834Y01464*
X03841Y01465*
X03846Y01469*
X03849Y01474*
X03851Y01481*
X03849Y01487*
X03846Y01492*
X03841Y01496*
X03834Y01497*
G37*
G36*
X03406Y01477D02*
X034Y01476D01*
X03395Y01472*
X03391Y01467*
X0339Y01461*
X03391Y01454*
X03395Y01449*
X034Y01445*
X03406Y01444*
X03413Y01445*
X03418Y01449*
X03421Y01454*
X03423Y01461*
X03421Y01467*
X03418Y01472*
X03413Y01476*
X03406Y01477*
G37*
G36*
X03732Y01434D02*
X03726Y01433D01*
X03721Y01429*
X03717Y01424*
X03716Y01418*
X03717Y01411*
X03721Y01406*
X03726Y01402*
X03732Y01401*
X03739Y01402*
X03744Y01406*
X03747Y01411*
X03749Y01418*
X03747Y01424*
X03744Y01429*
X03739Y01433*
X03732Y01434*
G37*
G36*
X03407Y01427D02*
X03401Y01426D01*
X03395Y01422*
X03392Y01417*
X0339Y01411*
X03392Y01405*
X03395Y014*
X03391Y01397*
X03386Y01401*
X03379Y01402*
X03373Y01401*
X03368Y01397*
X03364Y01392*
X03363Y01386*
X03364Y01379*
X03368Y01374*
X03373Y0137*
X03379Y01369*
X03385Y0137*
X03388Y01368*
X03389Y01367*
X03388Y01363*
X03389Y01357*
X03392Y01353*
X03392Y01352*
X03389Y01349*
X03388Y01349*
X03386Y01351*
X03379Y01352*
X03373Y01351*
X03368Y01347*
X03364Y01342*
X03363Y01336*
X03364Y01329*
X03368Y01324*
X03373Y0132*
X03379Y01319*
X03386Y0132*
X03391Y01324*
X03394Y01329*
X03396Y01336*
X03394Y01342*
X03392Y01345*
X03392Y01346*
X03395Y0135*
X03396Y01349*
X03398Y01348*
X03404Y01347*
X03411Y01348*
X03416Y01351*
X03419Y01357*
X03421Y01363*
X03419Y01369*
X03416Y01374*
X03411Y01378*
X03404Y01379*
X03399Y01378*
X03396Y0138*
X03395Y01382*
X03396Y01386*
X03394Y01392*
X03391Y01396*
X03395Y01399*
X03401Y01396*
X03407Y01395*
X03413Y01396*
X03418Y01399*
X03422Y01405*
X03423Y01411*
X03422Y01417*
X03418Y01422*
X03413Y01426*
X03407Y01427*
G37*
G36*
X03549Y01457D02*
X03543Y01456D01*
X03538Y01452*
X03534Y01447*
X03533Y01441*
X03534Y01434*
X03538Y01429*
Y01424*
X03534Y01419*
X03533Y01413*
X03534Y01406*
X03538Y01401*
X03543Y01397*
X03549Y01396*
X03556Y01397*
X03561Y01401*
X03564Y01406*
X03566Y01413*
X03564Y01419*
X03561Y01424*
Y01429*
X03564Y01434*
X03566Y01441*
X03564Y01447*
X03561Y01452*
X03556Y01456*
X03549Y01457*
G37*
G36*
X03571Y01328D02*
X03564Y01326D01*
X03557Y01322*
X03553Y01316*
X03552Y01308*
X03553Y01301*
X03557Y01295*
X03564Y01291*
X03571Y01289*
X03578Y01291*
X03584Y01295*
X03589Y01301*
X0359Y01308*
X03589Y01316*
X03584Y01322*
X03578Y01326*
X03571Y01328*
G37*
G36*
X04366Y01045D02*
X04289D01*
Y00968*
X04366*
Y01045*
G37*
G36*
X05327Y01046D02*
X05317Y01045D01*
X05308Y01041*
X053Y01034*
X05294Y01026*
X0529Y01017*
X05288Y01007*
X0529Y00997*
X05294Y00988*
X053Y0098*
X05308Y00973*
X05317Y00969*
X05327Y00968*
X05337Y00969*
X05347Y00973*
X05355Y0098*
X05361Y00988*
X05365Y00997*
X05366Y01007*
X05365Y01017*
X05361Y01026*
X05355Y01034*
X05347Y01041*
X05337Y01045*
X05327Y01046*
G37*
G36*
X05127D02*
X05117Y01045D01*
X05108Y01041*
X051Y01034*
X05094Y01026*
X0509Y01017*
X05088Y01007*
X0509Y00997*
X05094Y00988*
X051Y0098*
X05108Y00973*
X05117Y00969*
X05127Y00968*
X05137Y00969*
X05147Y00973*
X05155Y0098*
X05161Y00988*
X05165Y00997*
X05166Y01007*
X05165Y01017*
X05161Y01026*
X05155Y01034*
X05147Y01041*
X05137Y01045*
X05127Y01046*
G37*
G36*
X04927D02*
X04917Y01045D01*
X04908Y01041*
X049Y01034*
X04894Y01026*
X0489Y01017*
X04888Y01007*
X0489Y00997*
X04894Y00988*
X049Y0098*
X04908Y00973*
X04917Y00969*
X04927Y00968*
X04937Y00969*
X04947Y00973*
X04955Y0098*
X04961Y00988*
X04965Y00997*
X04966Y01007*
X04965Y01017*
X04961Y01026*
X04955Y01034*
X04947Y01041*
X04937Y01045*
X04927Y01046*
G37*
G36*
X03617Y00982D02*
X03604Y00981D01*
X03591Y00977*
X0358Y00971*
X03569Y00963*
X03561Y00952*
X03555Y00941*
X03551Y00928*
X0355Y00915*
X03551Y00902*
X03555Y00889*
X03561Y00877*
X03569Y00867*
X0358Y00859*
X03591Y00853*
X03604Y00849*
X03617Y00847*
X0363Y00849*
X03643Y00853*
X03654Y00859*
X03665Y00867*
X03673Y00877*
X03679Y00889*
X03683Y00902*
X03684Y00915*
X03683Y00928*
X03679Y00941*
X03673Y00952*
X03665Y00963*
X03654Y00971*
X03643Y00977*
X0363Y00981*
X03617Y00982*
G37*
G36*
X05578Y00936D02*
X05566Y00934D01*
X05555Y0093*
X05545Y00923*
X05538Y00913*
X05533Y00902*
X05532Y0089*
X05533Y00878*
X05538Y00867*
X05545Y00858*
X05555Y0085*
X05566Y00846*
X05578Y00844*
X0559Y00846*
X05601Y0085*
X0561Y00858*
X05617Y00867*
X05622Y00878*
X05624Y0089*
X05622Y00902*
X05617Y00913*
X0561Y00923*
X05601Y0093*
X0559Y00934*
X05578Y00936*
G37*
G36*
X03395Y04238D02*
X03389Y04237D01*
X03384Y04233*
X0338Y04228*
X03379Y04222*
X0338Y04215*
X03384Y0421*
X03389Y04206*
X03395Y04205*
X03402Y04206*
X03407Y0421*
X0341Y04215*
X03412Y04222*
X0341Y04228*
X03407Y04233*
X03402Y04237*
X03395Y04238*
G37*
G36*
X02888Y04237D02*
X02882Y04236D01*
X02877Y04232*
X02873Y04227*
X02872Y04221*
X02873Y04214*
X02877Y04209*
X02882Y04205*
X02888Y04204*
X02895Y04205*
X029Y04209*
X02903Y04214*
X02905Y04221*
X02903Y04227*
X029Y04232*
X02895Y04236*
X02888Y04237*
G37*
G36*
X0229Y04233D02*
X02284Y04232D01*
X02279Y04228*
X02275Y04223*
X02274Y04217*
X02275Y0421*
X02279Y04205*
X02284Y04201*
X0229Y042*
X02297Y04201*
X02302Y04205*
X02305Y0421*
X02307Y04217*
X02305Y04223*
X02302Y04228*
X02297Y04232*
X0229Y04233*
G37*
G36*
X04387Y04222D02*
X04381Y04221D01*
X04376Y04217*
X04372Y04212*
X04371Y04206*
X04372Y04199*
X04376Y04194*
X04381Y0419*
X04387Y04189*
X04394Y0419*
X04399Y04194*
X04402Y04199*
X04404Y04206*
X04402Y04212*
X04399Y04217*
X04394Y04221*
X04387Y04222*
G37*
G36*
X0491Y04219D02*
X04904Y04218D01*
X04899Y04214*
X04895Y04209*
X04894Y04203*
X04895Y04196*
X04899Y04191*
X04904Y04187*
X0491Y04186*
X04917Y04187*
X04922Y04191*
X04925Y04196*
X04927Y04203*
X04925Y04209*
X04922Y04214*
X04917Y04218*
X0491Y04219*
G37*
G36*
X03958Y04152D02*
X03951Y04151D01*
X03945Y04148*
X03939Y04144*
X03935Y04139*
X03933Y04132*
X03932Y04126*
X03933Y04119*
X03935Y04113*
X03939Y04107*
X03945Y04103*
X03951Y04101*
X03958Y041*
X03964Y04101*
X03971Y04103*
X03976Y04107*
X0398Y04113*
X03983Y04119*
X03984Y04126*
X03983Y04132*
X0398Y04139*
X03976Y04144*
X03971Y04148*
X03964Y04151*
X03958Y04152*
G37*
G36*
X03784D02*
X03778Y04151D01*
X03771Y04148*
X03766Y04144*
X03762Y04139*
X03759Y04132*
X03758Y04126*
X03759Y04119*
X03762Y04113*
X03766Y04107*
X03771Y04103*
X03778Y04101*
X03784Y041*
X03791Y04101*
X03797Y04103*
X03803Y04107*
X03807Y04113*
X03809Y04119*
X0381Y04126*
X03809Y04132*
X03807Y04139*
X03803Y04144*
X03797Y04148*
X03791Y04151*
X03784Y04152*
G37*
G36*
X04754Y04132D02*
X04748Y04131D01*
X04743Y04127*
X04739Y04122*
X04738Y04115*
X04739Y04109*
X04743Y04104*
X04748Y041*
X04754Y04099*
X0476Y041*
X04766Y04104*
X04769Y04109*
X04771Y04115*
X04769Y04122*
X04766Y04127*
X0476Y04131*
X04754Y04132*
G37*
G36*
X02146Y0412D02*
X02139Y04118D01*
X02134Y04115*
X02131Y0411*
X02129Y04103*
X02131Y04097*
X02134Y04092*
X02139Y04088*
X02146Y04087*
X02152Y04088*
X02157Y04092*
X02161Y04097*
X02162Y04103*
X02161Y0411*
X02157Y04115*
X02152Y04118*
X02146Y0412*
G37*
G36*
X0522Y04102D02*
X05214Y04101D01*
X05208Y04098*
X05205Y04092*
X05204Y04086*
X05205Y0408*
X05208Y04075*
X05214Y04071*
X0522Y0407*
X05226Y04071*
X05232Y04075*
X05235Y0408*
X05236Y04086*
X05235Y04092*
X05232Y04098*
X05226Y04101*
X0522Y04102*
G37*
G36*
X02253D02*
X02247Y04101D01*
X02242Y04098*
X02238Y04092*
X02237Y04086*
X02238Y0408*
X02242Y04075*
X02247Y04071*
X02253Y0407*
X0226Y04071*
X02265Y04075*
X02269Y0408*
X0227Y04086*
X02269Y04092*
X02265Y04098*
X0226Y04101*
X02253Y04102*
G37*
G36*
X03504Y04102D02*
X03498Y04101D01*
X03493Y04097*
X03489Y04092*
X03488Y04086*
X03489Y04079*
X03493Y04074*
X03498Y0407*
X03504Y04069*
X03511Y0407*
X03516Y04074*
X03519Y04079*
X03521Y04086*
X03519Y04092*
X03516Y04097*
X03511Y04101*
X03504Y04102*
G37*
G36*
X03294Y04127D02*
X03284Y04126D01*
X03274Y04121*
X03265Y04115*
X03259Y04106*
X03254Y04096*
X03253Y04086*
X03254Y04075*
X03259Y04065*
X03265Y04056*
X03274Y0405*
X03284Y04046*
X03294Y04044*
X03305Y04046*
X03315Y0405*
X03324Y04056*
X0333Y04065*
X03334Y04075*
X03336Y04086*
X03334Y04096*
X0333Y04106*
X03324Y04115*
X03315Y04121*
X03305Y04126*
X03294Y04127*
G37*
G36*
X02994D02*
X02984Y04126D01*
X02974Y04121*
X02965Y04115*
X02959Y04106*
X02954Y04096*
X02953Y04086*
X02954Y04075*
X02959Y04065*
X02965Y04056*
X02974Y0405*
X02984Y04046*
X02994Y04044*
X03005Y04046*
X03015Y0405*
X03024Y04056*
X0303Y04065*
X03034Y04075*
X03036Y04086*
X03034Y04096*
X0303Y04106*
X03024Y04115*
X03015Y04121*
X03005Y04126*
X02994Y04127*
G37*
G36*
X03777Y04039D02*
X03771Y04038D01*
X03766Y04034*
X03762Y04029*
X03761Y04023*
X03762Y04016*
X03766Y04011*
X03771Y04007*
X03777Y04006*
X03784Y04007*
X03789Y04011*
X03792Y04016*
X03794Y04023*
X03792Y04029*
X03789Y04034*
X03784Y04038*
X03777Y04039*
G37*
G36*
X06164Y04108D02*
X06075D01*
X06061Y04107*
X06049Y04101*
X06038Y04093*
X06029Y04082*
X06024Y04069*
X06022Y04056*
X06024Y04042*
X06029Y04029*
X06038Y04018*
X06049Y0401*
X06061Y04005*
X06075Y04003*
X06164*
X06177Y04005*
X0619Y0401*
X06201Y04018*
X06209Y04029*
X06215Y04042*
X06216Y04056*
X06215Y04069*
X06209Y04082*
X06201Y04093*
X0619Y04101*
X06177Y04107*
X06164Y04108*
G37*
G36*
X02353Y04034D02*
X02347Y04032D01*
X02341Y04029*
X02338Y04023*
X02337Y04017*
X02338Y04011*
X02341Y04006*
X02347Y04002*
X02353Y04001*
X02359Y04002*
X02364Y04006*
X02368Y04011*
X02369Y04017*
X02368Y04023*
X02364Y04029*
X02359Y04032*
X02353Y04034*
G37*
G36*
X05723Y04083D02*
X05708Y04081D01*
X05694Y04075*
X05682Y04066*
X05673Y04054*
X05667Y0404*
X05665Y04025*
X05667Y0401*
X05673Y03996*
X05682Y03984*
X05694Y03975*
X05708Y03969*
X05723Y03967*
X05738Y03969*
X05752Y03975*
X05764Y03984*
X05773Y03996*
X05779Y0401*
X05781Y04025*
X05779Y0404*
X05773Y04054*
X05764Y04066*
X05752Y04075*
X05738Y04081*
X05723Y04083*
G37*
G36*
X04393Y03992D02*
X04387Y03991D01*
X04382Y03987*
X04378Y03982*
X04377Y03976*
X04378Y0397*
X04382Y03964*
X04387Y03961*
X04393Y0396*
X04399Y03961*
X04405Y03964*
X04408Y0397*
X0441Y03976*
X04408Y03982*
X04405Y03987*
X04399Y03991*
X04393Y03992*
G37*
G36*
X02084Y03912D02*
X02078Y03911D01*
X02073Y03907*
X02069Y03902*
X02068Y03896*
X02069Y03889*
X02069Y03889*
X02066Y03885*
X02066Y03886*
X02059Y03887*
X02053Y03886*
X02048Y03882*
X02044Y03877*
X02043Y03871*
X02044Y03864*
X02048Y03859*
X02053Y03855*
X02059Y03854*
X02066Y03855*
X02071Y03859*
X02074Y03864*
X02076Y03871*
X02074Y03877*
X02074Y03877*
X02078Y03881*
X02078Y0388*
X02084Y03879*
X02091Y0388*
X02096Y03884*
X02099Y03889*
X02101Y03896*
X02099Y03902*
X02096Y03907*
X02091Y03911*
X02084Y03912*
G37*
G36*
X05934Y04034D02*
X05921Y04033D01*
X05908Y04027*
X05897Y04019*
X05889Y04008*
X05883Y03995*
X05882Y03982*
Y03893*
X05883Y0388*
X05889Y03867*
X05897Y03856*
X05908Y03847*
X05921Y03842*
X05934Y0384*
X05948Y03842*
X05961Y03847*
X05972Y03856*
X0598Y03867*
X05985Y0388*
X05987Y03893*
Y03982*
X05985Y03995*
X0598Y04008*
X05972Y04019*
X05961Y04027*
X05948Y04033*
X05934Y04034*
G37*
G36*
X03699Y03852D02*
X03693Y03851D01*
X03688Y03847*
X03684Y03842*
X03683Y03836*
X03684Y03829*
X03688Y03824*
X03693Y0382*
X03699Y03819*
X03706Y0382*
X03711Y03824*
X03714Y03829*
X03716Y03836*
X03714Y03842*
X03711Y03847*
X03706Y03851*
X03699Y03852*
G37*
G36*
X03014Y03847D02*
X03008Y03846D01*
X03003Y03842*
X02999Y03837*
X02998Y03831*
X02999Y03824*
X03003Y03819*
X03008Y03815*
X03014Y03814*
X03021Y03815*
X03026Y03819*
X03029Y03824*
X03031Y03831*
X03029Y03837*
X03026Y03842*
X03021Y03846*
X03014Y03847*
G37*
G36*
X05723Y03902D02*
X05708Y039D01*
X05694Y03894*
X05682Y03885*
X05673Y03873*
X05667Y03859*
X05665Y03844*
X05667Y03829*
X05673Y03815*
X05682Y03803*
X05694Y03794*
X05708Y03788*
X05723Y03786*
X05738Y03788*
X05752Y03794*
X05764Y03803*
X05773Y03815*
X05779Y03829*
X05781Y03844*
X05779Y03859*
X05773Y03873*
X05764Y03885*
X05752Y03894*
X05738Y039*
X05723Y03902*
G37*
G36*
X03269Y03804D02*
X03263Y03803D01*
X03258Y03799*
X03254Y03794*
X03253Y03788*
X03254Y03781*
X03258Y03776*
X03263Y03772*
X03269Y03771*
X03276Y03772*
X03281Y03776*
X03284Y03781*
X03286Y03788*
X03284Y03794*
X03281Y03799*
X03276Y03803*
X03269Y03804*
G37*
G36*
X0286Y03803D02*
X02854Y03802D01*
X02849Y03798*
X02845Y03793*
X02844Y03787*
X02845Y0378*
X02849Y03775*
X02854Y03771*
X0286Y0377*
X02867Y03771*
X02872Y03775*
X02875Y0378*
X02877Y03787*
X02875Y03793*
X02872Y03798*
X02867Y03802*
X0286Y03803*
G37*
G36*
X06169Y03877D02*
X0607D01*
X06055Y03875*
X06041Y03869*
X06029Y0386*
X0602Y03848*
X06014Y03834*
X06012Y03819*
X06014Y03804*
X0602Y0379*
X06029Y03779*
X06041Y03769*
X06055Y03764*
X0607Y03762*
X06169*
X06183Y03764*
X06197Y03769*
X06209Y03779*
X06219Y0379*
X06224Y03804*
X06226Y03819*
X06224Y03834*
X06219Y03848*
X06209Y0386*
X06197Y03869*
X06183Y03875*
X06169Y03877*
G37*
G36*
X0383Y03778D02*
X03824Y03777D01*
X03819Y03773*
X03815Y03768*
X03814Y03762*
X03815Y03755*
X03819Y0375*
X03824Y03746*
X0383Y03745*
X03837Y03746*
X03842Y0375*
X03845Y03755*
X03847Y03762*
X03845Y03768*
X03842Y03773*
X03837Y03777*
X0383Y03778*
G37*
G36*
X02531Y03962D02*
X02514Y0396D01*
X02497Y03956*
X02482Y0395*
X02467Y03941*
X02454Y0393*
X02443Y03917*
X02434Y03902*
X02428Y03887*
X02424Y0387*
X02423Y03853*
X02424Y03836*
X02428Y0382*
X02434Y03804*
X02443Y03789*
X02454Y03777*
X02467Y03766*
X02482Y03757*
X02497Y0375*
X02514Y03746*
X02531Y03745*
X02548Y03746*
X02564Y0375*
X0258Y03757*
X02595Y03766*
X02608Y03777*
X02619Y03789*
X02627Y03804*
X02634Y0382*
X02638Y03836*
X02639Y03853*
X02638Y0387*
X02634Y03887*
X02627Y03902*
X02619Y03917*
X02608Y0393*
X02595Y03941*
X0258Y0395*
X02564Y03956*
X02548Y0396*
X02531Y03962*
G37*
G36*
X03699Y03767D02*
X03693Y03766D01*
X03688Y03762*
X03684Y03757*
X03683Y03751*
X03684Y03744*
X03688Y03739*
X03693Y03735*
X03699Y03734*
X03706Y03735*
X03711Y03739*
X03714Y03744*
X03716Y03751*
X03714Y03757*
X03711Y03762*
X03706Y03766*
X03699Y03767*
G37*
G36*
X02993D02*
X02987Y03766D01*
X02981Y03762*
X02978Y03757*
X02977Y03751*
X02978Y03744*
X02981Y03739*
X02987Y03735*
X02993Y03734*
X02999Y03735*
X03004Y03739*
X03008Y03744*
X03009Y03751*
X03008Y03757*
X03004Y03762*
X02999Y03766*
X02993Y03767*
G37*
G36*
X02258Y03757D02*
X02252Y03756D01*
X02247Y03752*
X02243Y03747*
X02242Y03741*
X02243Y03734*
X02247Y03729*
X02252Y03725*
X02258Y03724*
X02265Y03725*
X0227Y03729*
X02273Y03734*
X02275Y03741*
X02273Y03747*
X0227Y03752*
X02265Y03756*
X02258Y03757*
G37*
G36*
X04523Y03752D02*
X04517Y03751D01*
X04512Y03747*
X04508Y03742*
X04507Y03736*
X04508Y03729*
X04512Y03724*
X04517Y03721*
X04523Y03719*
X04529Y03721*
X04535Y03724*
X04538Y03729*
X04539Y03736*
X04538Y03742*
X04535Y03747*
X04529Y03751*
X04523Y03752*
G37*
G36*
X02724Y03745D02*
X02718Y03744D01*
X02713Y0374*
X02709Y03735*
X02708Y03729*
X02709Y03722*
X02713Y03717*
X02718Y03713*
X02724Y03712*
X02731Y03713*
X02736Y03717*
X02739Y03722*
X02741Y03729*
X02739Y03735*
X02736Y0374*
X02731Y03744*
X02724Y03745*
G37*
G36*
X04437Y03677D02*
X0443Y03676D01*
X04425Y03672*
X04421Y03667*
X0442Y03661*
X04421Y03655*
X04425Y03649*
X0443Y03646*
X04437Y03645*
X04443Y03646*
X04448Y03649*
X04452Y03655*
X04453Y03661*
X04452Y03667*
X04448Y03672*
X04443Y03676*
X04437Y03677*
G37*
G36*
X04385D02*
X04379Y03676D01*
X04374Y03672*
X0437Y03667*
X04369Y03661*
X0437Y03655*
X04374Y03649*
X04379Y03646*
X04385Y03645*
X04392Y03646*
X04397Y03649*
X044Y03655*
X04402Y03661*
X044Y03667*
X04397Y03672*
X04392Y03676*
X04385Y03677*
G37*
G36*
X02422Y03624D02*
X02413Y03623D01*
X02405Y03617*
X024Y0361*
X02398Y03601*
X024Y03592*
X02405Y03584*
X02413Y03579*
X02422Y03577*
X02431Y03579*
X02438Y03584*
X02443Y03592*
X02445Y03601*
X02443Y0361*
X02438Y03617*
X02431Y03623*
X02422Y03624*
G37*
G36*
X05733Y03572D02*
X05727Y03571D01*
X05722Y03567*
X05718Y03562*
X05717Y03556*
X05718Y03549*
X05722Y03544*
X05727Y0354*
X05733Y03539*
X0574Y0354*
X05745Y03544*
X05748Y03549*
X0575Y03556*
X05748Y03562*
X05745Y03567*
X0574Y03571*
X05733Y03572*
G37*
G36*
X05676Y03562D02*
X0567Y03561D01*
X05665Y03557*
X05661Y03552*
X0566Y03546*
X05661Y03539*
X05665Y03534*
X0567Y0353*
X05676Y03529*
X05683Y0353*
X05688Y03534*
X05691Y03539*
X05693Y03546*
X05691Y03552*
X05688Y03557*
X05683Y03561*
X05676Y03562*
G37*
G36*
X02434D02*
X02428Y03561D01*
X02423Y03557*
X02419Y03552*
X02418Y03546*
X02419Y03539*
X02423Y03534*
X02428Y0353*
X02434Y03529*
X02441Y0353*
X02446Y03534*
X02449Y03539*
X02451Y03546*
X02449Y03552*
X02446Y03557*
X02441Y03561*
X02434Y03562*
G37*
G36*
X02254Y03552D02*
X02248Y03551D01*
X02243Y03547*
X02239Y03542*
X02238Y03536*
X02239Y03529*
X02243Y03524*
X02248Y0352*
X02254Y03519*
X02261Y0352*
X02266Y03524*
X02269Y03529*
X02271Y03536*
X02269Y03542*
X02266Y03547*
X02261Y03551*
X02254Y03552*
G37*
G36*
X02389Y03497D02*
X02383Y03496D01*
X02378Y03492*
X02374Y03487*
X02373Y03481*
X02374Y03474*
X02378Y03469*
X02383Y03465*
X02389Y03464*
X02396Y03465*
X02401Y03469*
X02404Y03474*
X02406Y03481*
X02404Y03487*
X02401Y03492*
X02396Y03496*
X02389Y03497*
G37*
G36*
X02422Y03467D02*
X02413Y03465D01*
X02405Y0346*
X024Y03452*
X02398Y03443*
X024Y03434*
X02405Y03427*
X02413Y03422*
X02422Y0342*
X02431Y03422*
X02438Y03427*
X02443Y03434*
X02445Y03443*
X02443Y03452*
X02438Y0346*
X02431Y03465*
X02422Y03467*
G37*
G36*
X02321Y03377D02*
X02315Y03376D01*
X0231Y03372*
X02306Y03367*
X02305Y03361*
X02306Y03354*
X0231Y03349*
X02315Y03345*
X02321Y03344*
X02327Y03345*
X02333Y03349*
X02336Y03354*
X02337Y03361*
X02336Y03367*
X02333Y03372*
X02327Y03376*
X02321Y03377*
G37*
G36*
X04438Y0337D02*
X04432Y03369D01*
X04427Y03366*
X04423Y0336*
X04422Y03354*
X04423Y03348*
X04427Y03342*
X04432Y03339*
X04438Y03338*
X04445Y03339*
X0445Y03342*
X04454Y03348*
X04455Y03354*
X04454Y0336*
X0445Y03366*
X04445Y03369*
X04438Y0337*
G37*
G36*
X02259Y03277D02*
X02253Y03276D01*
X02248Y03272*
X02244Y03267*
X02243Y03261*
X02244Y03254*
X02248Y03249*
X02253Y03245*
X02259Y03244*
X02266Y03245*
X02271Y03249*
X02274Y03254*
X02276Y03261*
X02274Y03267*
X02271Y03272*
X02266Y03276*
X02259Y03277*
G37*
G36*
X02205Y03216D02*
X02199Y03215D01*
X02194Y03211*
X0219Y03206*
X02189Y032*
X0219Y03193*
X02194Y03188*
X02199Y03184*
X02205Y03183*
X02212Y03184*
X02217Y03188*
X0222Y03193*
X02222Y032*
X0222Y03206*
X02217Y03211*
X02212Y03215*
X02205Y03216*
G37*
G36*
X04477Y03151D02*
X04471Y0315D01*
X04466Y03146*
X04462Y03141*
X04461Y03135*
X04462Y03128*
X04466Y03123*
X04471Y03119*
X04477Y03118*
X04484Y03119*
X04489Y03123*
X04492Y03128*
X04494Y03135*
X04492Y03141*
X04489Y03146*
X04484Y0315*
X04477Y03151*
G37*
G36*
X04431D02*
X04425Y0315D01*
X0442Y03146*
X04416Y03141*
X04415Y03135*
X04416Y03128*
X0442Y03123*
X04425Y03119*
X04431Y03118*
X04438Y03119*
X04443Y03123*
X04446Y03128*
X04448Y03135*
X04446Y03141*
X04443Y03146*
X04438Y0315*
X04431Y03151*
G37*
G36*
X06274Y02966D02*
X06268Y02964D01*
X06263Y02961*
X06259Y02956*
X06258Y02949*
X06259Y02943*
X06263Y02938*
X06268Y02934*
X06274Y02933*
X0628Y02934*
X06286Y02938*
X06289Y02943*
X0629Y02949*
X06289Y02956*
X06286Y02961*
X0628Y02964*
X06274Y02966*
G37*
G36*
X04794Y02824D02*
X04788Y02823D01*
X04782Y02819*
X04779Y02814*
X04777Y02808*
X04779Y02801*
X04782Y02796*
X04788Y02793*
X04794Y02791*
X048Y02793*
X04805Y02796*
X04809Y02801*
X0481Y02808*
X04809Y02814*
X04805Y02819*
X048Y02823*
X04794Y02824*
G37*
G36*
X05578Y02534D02*
X05566Y02533D01*
X05555Y02528*
X05545Y02521*
X05538Y02511*
X05533Y025*
X05532Y02489*
X05533Y02477*
X05538Y02466*
X05545Y02456*
X05555Y02449*
X05566Y02444*
X05578Y02443*
X0559Y02444*
X05601Y02449*
X0561Y02456*
X05617Y02466*
X05622Y02477*
X05624Y02489*
X05622Y025*
X05617Y02511*
X0561Y02521*
X05601Y02528*
X0559Y02533*
X05578Y02534*
G37*
G36*
X06003Y02446D02*
X05997Y02445D01*
X05992Y02441*
X05988Y02436*
X05987Y0243*
X05988Y02423*
X05992Y02418*
X05997Y02415*
X06003Y02413*
X0601Y02415*
X06015Y02418*
X06019Y02423*
X0602Y0243*
X06019Y02436*
X06015Y02441*
X0601Y02445*
X06003Y02446*
G37*
G36*
X069Y03647D02*
X06885Y03645D01*
X06871Y03639*
X06859Y0363*
X0685Y03618*
X06844Y03604*
X06842Y03589*
X06844Y03574*
X0685Y0356*
X06859Y03548*
X06871Y03539*
X06885Y03533*
X069Y03531*
X06915Y03533*
X06929Y03539*
X06941Y03548*
X0695Y0356*
X06955Y03574*
X06957Y03589*
X06955Y03604*
X0695Y03618*
X06941Y0363*
X06929Y03639*
X06915Y03645*
X069Y03647*
G37*
G36*
X06734D02*
X06719Y03645D01*
X06705Y03639*
X06694Y0363*
X06684Y03618*
X06679Y03604*
X06677Y03589*
X06679Y03574*
X06684Y0356*
X06694Y03548*
X06705Y03539*
X06719Y03533*
X06734Y03531*
X06749Y03533*
X06763Y03539*
X06775Y03548*
X06784Y0356*
X0679Y03574*
X06792Y03589*
X0679Y03604*
X06784Y03618*
X06775Y0363*
X06763Y03639*
X06749Y03645*
X06734Y03647*
G37*
G36*
X06569D02*
X06554Y03645D01*
X0654Y03639*
X06528Y0363*
X06519Y03618*
X06513Y03604*
X06511Y03589*
X06513Y03574*
X06519Y0356*
X06528Y03548*
X0654Y03539*
X06554Y03533*
X06569Y03531*
X06584Y03533*
X06598Y03539*
X0661Y03548*
X06619Y0356*
X06625Y03574*
X06627Y03589*
X06625Y03604*
X06619Y03618*
X0661Y0363*
X06598Y03639*
X06584Y03645*
X06569Y03647*
G37*
G36*
X06509Y03472D02*
X06503Y03471D01*
X06498Y03467*
X06494Y03462*
X06493Y03456*
X06494Y03449*
X06498Y03444*
X06503Y0344*
X06509Y03439*
X06516Y0344*
X06521Y03444*
X06524Y03449*
X06526Y03456*
X06524Y03462*
X06521Y03467*
X06516Y03471*
X06509Y03472*
G37*
G36*
X06479Y03442D02*
X06473Y03441D01*
X06468Y03437*
X06464Y03432*
X06463Y03426*
X06464Y03419*
X06468Y03414*
X06473Y0341*
X06479Y03409*
X06486Y0341*
X06491Y03414*
X06494Y03419*
X06496Y03426*
X06494Y03432*
X06491Y03437*
X06486Y03441*
X06479Y03442*
G37*
G36*
X06447Y03412D02*
X06441Y03411D01*
X06436Y03407*
X06432Y03402*
X06431Y03396*
X06432Y03389*
X06436Y03384*
X06441Y0338*
X06447Y03379*
X06453Y0338*
X06459Y03384*
X06462Y03389*
X06463Y03396*
X06462Y03402*
X06459Y03407*
X06453Y03411*
X06447Y03412*
G37*
G36*
X06409Y03387D02*
X06403Y03386D01*
X06398Y03382*
X06394Y03377*
X06393Y03371*
X06394Y03364*
X06398Y03359*
X06403Y03355*
X06409Y03354*
X06416Y03355*
X06421Y03359*
X06424Y03364*
X06426Y03371*
X06424Y03377*
X06421Y03382*
X06416Y03386*
X06409Y03387*
G37*
G36*
X06648Y03357D02*
X06642Y03356D01*
X06637Y03352*
X06633Y03347*
X06632Y03341*
X06633Y03334*
X06637Y03329*
X06642Y03325*
X06648Y03324*
X06655Y03325*
X0666Y03329*
X06663Y03334*
X06665Y03341*
X06663Y03347*
X0666Y03352*
X06655Y03356*
X06648Y03357*
G37*
G36*
X06354Y03347D02*
X06348Y03346D01*
X06343Y03342*
X06339Y03337*
X06338Y03331*
X06339Y03324*
X06343Y03319*
X06348Y03316*
X06354Y03314*
X0636Y03316*
X06366Y03319*
X06369Y03324*
X06371Y03331*
X06369Y03337*
X06366Y03342*
X0636Y03346*
X06354Y03347*
G37*
G36*
X06444Y03307D02*
X06438Y03306D01*
X06433Y03302*
X06429Y03297*
X06428Y03291*
X06429Y03284*
X06433Y03279*
X06438Y03275*
X06444Y03274*
X06451Y03275*
X06456Y03279*
X06459Y03284*
X06461Y03291*
X06459Y03297*
X06456Y03302*
X06451Y03306*
X06444Y03307*
G37*
G36*
X06334Y03282D02*
X06328Y03281D01*
X06323Y03277*
X06319Y03272*
X06318Y03266*
X06319Y03259*
X06323Y03254*
X06328Y0325*
X06334Y03249*
X06341Y0325*
X06346Y03254*
X06349Y03259*
X06351Y03266*
X06349Y03272*
X06346Y03277*
X06341Y03281*
X06334Y03282*
G37*
G36*
X06476Y03247D02*
X0647Y03246D01*
X06465Y03242*
X06461Y03237*
X0646Y03231*
X06461Y03224*
X06465Y03219*
X0647Y03215*
X06476Y03214*
X06483Y03215*
X06488Y03219*
X06491Y03224*
X06493Y03231*
X06491Y03237*
X06488Y03242*
X06483Y03246*
X06476Y03247*
G37*
G36*
X06262Y03236D02*
X06256Y03235D01*
X06251Y03231*
X06247Y03226*
X06246Y0322*
X06247Y03213*
X06251Y03208*
X06256Y03204*
X06262Y03203*
X06269Y03204*
X06269Y03205*
X06272Y03201*
X06272Y03201*
X06271Y03195*
X06272Y03188*
X06276Y03183*
X06281Y03179*
X06287Y03178*
X06294Y03179*
X06299Y03183*
X06302Y03188*
X06304Y03195*
X06302Y03201*
X06299Y03206*
X06294Y0321*
X06287Y03211*
X06281Y0321*
X06281Y03209*
X06277Y03213*
X06277Y03213*
X06279Y0322*
X06277Y03226*
X06274Y03231*
X06269Y03235*
X06262Y03236*
G37*
G36*
X06439Y03207D02*
X06433Y03206D01*
X06428Y03202*
X06424Y03197*
X06423Y03191*
X06424Y03184*
X06428Y03179*
X06433Y03175*
X06439Y03174*
X06446Y03175*
X06451Y03179*
X06454Y03184*
X06456Y03191*
X06454Y03197*
X06451Y03202*
X06446Y03206*
X06439Y03207*
G37*
G36*
X06335Y03163D02*
X06329Y03162D01*
X06324Y03158*
X0632Y03153*
X06319Y03147*
X0632Y0314*
X06324Y03135*
X06329Y03132*
X06335Y0313*
X06342Y03132*
X06347Y03135*
X0635Y0314*
X06352Y03147*
X0635Y03153*
X06347Y03158*
X06342Y03162*
X06335Y03163*
G37*
G36*
X06647Y03146D02*
X06641Y03144D01*
X06636Y03141*
X06632Y03136*
X06631Y03129*
X06632Y03123*
X06636Y03118*
X06641Y03114*
X06647Y03113*
X06653Y03114*
X06659Y03118*
X06662Y03123*
X06663Y03129*
X06662Y03136*
X06659Y03141*
X06653Y03144*
X06647Y03146*
G37*
G36*
X06304Y03137D02*
X06298Y03136D01*
X06293Y03132*
X06289Y03127*
X06288Y03121*
X06289Y03114*
X06293Y03109*
X06298Y03105*
X06304Y03104*
X06311Y03105*
X06316Y03109*
X06319Y03114*
X06321Y03121*
X06319Y03127*
X06316Y03132*
X06311Y03136*
X06304Y03137*
G37*
G36*
X06456Y03025D02*
X0645Y03024D01*
X06445Y0302*
X06441Y03015*
X0644Y03009*
X06441Y03002*
X06445Y02997*
X0645Y02993*
X06456Y02992*
X06463Y02993*
X06468Y02997*
X06471Y03002*
X06473Y03009*
X06471Y03015*
X06468Y0302*
X06463Y03024*
X06456Y03025*
G37*
G36*
X06649Y0302D02*
X06643Y03019D01*
X06638Y03015*
X06634Y0301*
X06633Y03003*
X06634Y02997*
X06638Y02992*
X06643Y02988*
X06649Y02987*
X06655Y02988*
X06661Y02992*
X06664Y02997*
X06665Y03003*
X06664Y0301*
X06661Y03015*
X06655Y03019*
X06649Y0302*
G37*
G36*
X06362Y02969D02*
X06355Y02967D01*
X0635Y02964*
X06347Y02959*
X06345Y02952*
X06347Y02946*
X0635Y02941*
X06355Y02937*
X06362Y02936*
X06368Y02937*
X06373Y02941*
X06377Y02946*
X06378Y02952*
X06377Y02959*
X06373Y02964*
X06368Y02967*
X06362Y02969*
G37*
G36*
X0645Y02756D02*
X06444Y02755D01*
X06439Y02751*
X06435Y02746*
X06434Y0274*
X06435Y02733*
X06439Y02728*
X06444Y02725*
X0645Y02723*
X06457Y02725*
X06462Y02728*
X06465Y02733*
X06467Y0274*
X06465Y02746*
X06462Y02751*
X06457Y02755*
X0645Y02756*
G37*
G36*
X06451Y02689D02*
X06445Y02688D01*
X0644Y02684*
X06436Y02679*
X06435Y02673*
X06436Y02666*
X0644Y02661*
X06445Y02658*
X06451Y02656*
X06458Y02658*
X06463Y02661*
X06466Y02666*
X06468Y02673*
X06466Y02679*
X06463Y02684*
X06458Y02688*
X06451Y02689*
G37*
G36*
X06452Y02622D02*
X06446Y02621D01*
X06441Y02617*
X06437Y02612*
X06436Y02606*
X06437Y026*
X06441Y02594*
X06446Y02591*
X06452Y02589*
X06459Y02591*
X06464Y02594*
X06467Y026*
X06469Y02606*
X06467Y02612*
X06464Y02617*
X06459Y02621*
X06452Y02622*
G37*
G36*
X0645Y02551D02*
X06444Y0255D01*
X06439Y02546*
X06435Y02541*
X06434Y02535*
X06435Y02529*
X06439Y02523*
X06444Y0252*
X0645Y02519*
X06457Y0252*
X06462Y02523*
X06465Y02529*
X06467Y02535*
X06465Y02541*
X06462Y02546*
X06457Y0255*
X0645Y02551*
G37*
G36*
Y02478D02*
X06444Y02477D01*
X06439Y02474*
X06435Y02468*
X06434Y02462*
X06435Y02456*
X06439Y02451*
X06444Y02447*
X0645Y02446*
X06457Y02447*
X06462Y02451*
X06465Y02456*
X06467Y02462*
X06465Y02468*
X06462Y02474*
X06457Y02477*
X0645Y02478*
G37*
G36*
X06607Y02192D02*
X06601Y02191D01*
X06596Y02187*
X06592Y02182*
X06591Y02176*
X06592Y02169*
X06596Y02164*
X06601Y0216*
X06607Y02159*
X06614Y0216*
X06619Y02164*
X06622Y02169*
X06624Y02176*
X06622Y02182*
X06619Y02187*
X06614Y02191*
X06607Y02192*
G37*
G36*
X06949Y02111D02*
X06943Y0211D01*
X06938Y02106*
X06934Y02101*
X06933Y02095*
X06934Y02088*
X06938Y02083*
X06943Y02079*
X06949Y02078*
X06956Y02079*
X06961Y02083*
X06964Y02088*
X06966Y02095*
X06964Y02101*
X06961Y02106*
X06956Y0211*
X06949Y02111*
G37*
G36*
X06978Y01847D02*
X06972Y01845D01*
X06967Y01842*
X06963Y01836*
X06962Y0183*
X06963Y01824*
X06967Y01819*
X06972Y01815*
X06978Y01814*
X06985Y01815*
X0699Y01819*
X06993Y01824*
X06995Y0183*
X06993Y01836*
X0699Y01842*
X06985Y01845*
X06978Y01847*
G37*
%LNtimingcard_pcb-3*%
%LPD*%
G54D14*
X02633Y02921D02*
Y0297D01*
X02632Y02971D02*
X02633Y0297D01*
X02397Y03279D02*
X02413Y03295D01*
X02334Y03279D02*
X02397D01*
X02415Y02792D02*
Y02823D01*
Y02792D02*
X02419Y02788D01*
X02394Y02845D02*
X02415Y02823D01*
X02434Y0298D02*
X02473D01*
X02421Y02967D02*
X02434Y0298D01*
X02398Y02949D02*
X02415Y02967D01*
X02421*
X02398Y02944D02*
Y02949D01*
X02385Y02854D02*
X02386D01*
X02394Y02846*
Y02845D02*
Y02846D01*
G54D19*
X0298Y00408D02*
D01*
X0298Y00408*
X0298Y00408*
X0298Y00407*
X02821Y00407D02*
D01*
X02821Y00407*
X02821Y00407*
X02821Y00407*
X0282Y00407*
X0282Y00406*
X0282Y00406*
X0282Y00406*
X02819Y00406*
X02819Y00405*
X02819Y00405*
X02819Y00405*
X02819Y00404*
X02819Y00404*
X02818Y00404*
X02818Y00403*
X02818Y00403*
Y00403*
X02469Y0041D02*
D01*
X02469Y0041*
X02469Y0041*
X02469Y0041*
X02469Y00409*
X02468Y00409*
X02468Y00409*
X02468Y00408*
X02468Y00408*
X02468Y00408*
X02468Y00407*
X02468Y00407*
X02854Y00364D02*
D01*
X02854Y00364*
X02854Y00363*
X02854Y00363*
X02854Y00363*
X02854Y00363*
X02854Y00363*
X02854Y00363*
X02854Y00363*
X02854Y00363*
X02854Y00363*
X02854Y00363*
X02854Y00362*
X02818Y00365D02*
D01*
X02818Y00365*
X02818Y00364*
X02818Y00364*
X02819Y00364*
X02819Y00364*
X02819Y00363*
X02819Y00363*
X02819Y00363*
X02819Y00363*
X02819Y00363*
X02819Y00363*
X02819Y00362*
X02664D02*
D01*
X02664Y00363*
X02665Y00363*
X02665Y00363*
X02665Y00363*
X02665Y00363*
X02665Y00363*
X02665Y00363*
X02665Y00363*
X02665Y00363*
X02665Y00364*
X02665Y00364*
X02665Y00364*
X02349Y00362D02*
D01*
X02349Y00363*
X0235Y00363*
X0235Y00363*
X0235Y00363*
X0235Y00363*
X0235Y00363*
X0235Y00363*
X0235Y00363*
X0235Y00364*
X0235Y00364*
X0235Y00364*
Y00364*
X02979Y00362D02*
D01*
X02979Y00363*
X02979Y00363*
X0298Y00363*
X0298Y00363*
X0298Y00363*
X0298Y00363*
X0298Y00363*
X0298Y00363*
X0298Y00363*
X0298Y00363*
X0298Y00364*
X0298Y00364*
X02349Y00329D02*
D01*
X02349Y00329*
X02349Y00328*
X02349Y00328*
X02349Y00328*
X02349Y00328*
X02349Y00328*
X02349Y00328*
X02349Y00328*
X02349Y00327*
X02349Y00327*
X02349Y00327*
Y00327*
X02348Y00137D02*
D01*
X02348Y00138*
X02348Y00138*
X02349Y00138*
X02349Y00138*
X02349Y00139*
X02349Y00139*
X02349Y00139*
X02349Y0014*
X02349Y0014*
X02349Y0014*
X02349Y00141*
X02349Y00141*
X02387Y00137D02*
D01*
X02388Y00138*
X02388Y00138*
X02388Y00138*
X02388Y00139*
X02389Y00139*
X02389Y0014*
X02389Y0014*
X02389Y00141*
X02389Y00141*
X02389Y00142*
X02389Y00142*
X02389Y00142*
X02466Y00137D02*
D01*
X02466Y00138*
X02467Y00138*
X02467Y00139*
X02467Y00139*
X02468Y0014*
X02468Y0014*
X02468Y00141*
X02468Y00141*
X02468Y00142*
X02468Y00142*
X02468Y00143*
X02468Y00143*
X02505Y00137D02*
D01*
X02506Y00138*
X02507Y00139*
X02508Y00141*
X02509Y00142*
X02509Y00143*
X0251Y00144*
X0251Y00146*
X02511Y00147*
X02511Y00148*
X02511Y0015*
X02511Y00151*
X02511Y00152*
X02663Y00137D02*
D01*
X02663Y00138*
X02663Y00138*
X02664Y00138*
X02664Y00138*
X02664Y00139*
X02664Y00139*
X02664Y00139*
X02664Y0014*
X02664Y0014*
X02664Y0014*
X02664Y00141*
X02664Y00141*
X02702Y00137D02*
D01*
X02703Y00138*
X02703Y00138*
X02703Y00138*
X02703Y00139*
X02704Y00139*
X02704Y0014*
X02704Y0014*
X02704Y00141*
X02704Y00141*
X02704Y00142*
X02704Y00142*
X02704Y00142*
X02821Y00324D02*
D01*
X02821Y00325*
X02821Y00325*
X02821Y00326*
X02821Y00326*
X02821Y00326*
X02821Y00327*
X0282Y00327*
X0282Y00328*
X0282Y00328*
X0282Y00328*
X02819Y00329*
X02819Y00329*
Y0014D02*
D01*
X02819Y0014*
X02819Y00139*
X02819Y00139*
X02819Y00139*
X0282Y00139*
X0282Y00138*
X0282Y00138*
X0282Y00138*
X0282Y00138*
X0282Y00138*
X0282Y00137*
X0282Y00137*
X02854Y0015D02*
D01*
X02854Y00149*
X02855Y00148*
X02855Y00146*
X02855Y00145*
X02855Y00144*
X02856Y00143*
X02856Y00142*
X02857Y00141*
X02858Y00139*
X02859Y00138*
X0286Y00138*
X0286Y00137*
X03019Y00329D02*
D01*
X03019Y00328*
X03019Y00328*
X03019Y00328*
X03019Y00328*
X03018Y00327*
X03018Y00327*
X03018Y00327*
X03018Y00326*
X03018Y00326*
X03018Y00326*
X03018Y00325*
X03018Y00325*
X03017Y00137D02*
D01*
X03018Y00138*
X03018Y00138*
X03018Y00138*
X03018Y00139*
X03019Y00139*
X03019Y0014*
X03019Y0014*
X03019Y00141*
X03019Y00141*
X03019Y00142*
X03019Y00142*
X03019Y00142*
X02979Y00329D02*
D01*
X02979Y00329*
X02979Y00328*
X02979Y00328*
X02979Y00328*
X02979Y00328*
X02979Y00328*
X02979Y00328*
X02979Y00327*
X02979Y00327*
X02979Y00327*
X02979Y00327*
X02979Y00327*
X02978Y00137D02*
D01*
X02978Y00138*
X02978Y00138*
X02979Y00138*
X02979Y00138*
X02979Y00139*
X02979Y00139*
X02979Y00139*
X02979Y0014*
X02979Y0014*
X02979Y0014*
X02979Y00141*
X02979Y00141*
X02979Y00111D02*
D01*
X02979Y00111*
X02979Y00111*
X02979Y00111*
X02979Y00111*
X02979Y00111*
X02979Y00111*
X02979Y00112*
X02979Y00112*
X02979Y00112*
X02979Y00112*
X02979Y00112*
X02979Y00112*
X02467Y00111D02*
D01*
X02467Y00111*
X02467Y00111*
X02467Y00111*
X02467Y00111*
X02467Y00111*
X02467*
D01*
X02467Y00111*
X02467Y00111*
X02468Y00111*
X02468Y00112*
X02468Y00112*
X02468Y00112*
X02468Y00113*
X02468Y00113*
X02468Y00113*
X02468Y00114*
X02468Y00114*
X02468Y00114*
X02664Y00111D02*
D01*
X02664Y00111*
X02664Y00111*
X02664Y00111*
X02664Y00111*
X02664Y00111*
X02664Y00111*
X02664Y00112*
X02664Y00112*
X02664Y00112*
X02664Y00112*
X02664Y00112*
Y00112*
X02854Y00125D02*
D01*
X02854Y00124*
X02855Y00123*
X02855Y00121*
X02855Y0012*
X02856Y00118*
X02856Y00117*
X02857Y00116*
X02858Y00114*
X02858Y00113*
X02859Y00112*
X0286Y00111*
X02861Y00111*
D01*
X02861Y00111*
X02861Y00111*
X02861Y00111*
X02861Y00111*
X02861Y00111*
X02703D02*
D01*
X02703Y00111*
X02703Y00111*
X02704Y00111*
X02704Y00112*
X02704Y00112*
X02704Y00112*
X02704Y00112*
X02704Y00113*
X02704Y00113*
X02704Y00113*
X02704Y00114*
X02704Y00114*
X02468Y00363D02*
Y00405D01*
Y00363D02*
X02468Y00362D01*
X02511Y00363D02*
Y00405D01*
Y00363D02*
X02511Y00362D01*
X0298Y00408D02*
X0298Y00409D01*
X0298Y00409*
X0298Y00364D02*
Y00407D01*
X02818Y00365D02*
Y00403D01*
X02469Y0041D02*
X02469Y0041D01*
X02468Y00405D02*
X02468Y00407D01*
X02469Y0041D02*
X02469Y0041D01*
X02854Y00364D02*
Y00405D01*
X02665Y00364D02*
Y00405D01*
X02704Y00363D02*
X02704Y00362D01*
X02704Y00363D02*
Y00405D01*
X0235Y00364D02*
Y00405D01*
X02389Y00363D02*
X02389Y00362D01*
X02389Y00363D02*
Y00405D01*
X03019Y00363D02*
X03019Y00362D01*
X03019Y00363D02*
Y00405D01*
X02349Y00141D02*
Y00329D01*
X02389Y00142D02*
Y00329D01*
X02468Y00143D02*
Y00329D01*
X02511Y00152D02*
Y00329D01*
X02664Y00141D02*
Y00329D01*
X02704Y00142D02*
Y00329D01*
X02819Y0014D02*
Y00329D01*
X02854Y0015D02*
Y00329D01*
X03019Y00142D02*
Y00329D01*
X02979Y00141D02*
Y00329D01*
G54D22*
X04053Y03641D02*
Y03697D01*
X03944Y03806D02*
X04053Y03697D01*
X02415Y03121D02*
X02418Y03118D01*
X02462Y03172D02*
X0249Y032D01*
X02334D02*
X02335Y03199D01*
X02509Y03121D02*
X02529D01*
X0249Y032D02*
X02509D01*
X0259Y03187D02*
X02591Y03186D01*
X02583Y03279D02*
X02589Y03285D01*
X02529Y03121D02*
X02591Y03184D01*
X02335Y03199D02*
X02414D01*
X02591Y03184D02*
Y03186D01*
X02589Y03287D02*
X0259Y03288D01*
X02509Y03279D02*
X02583D01*
X02589Y03285D02*
Y03287D01*
X02334Y03121D02*
X02415D01*
X01798Y0013D02*
Y00355D01*
X01896Y00735D02*
X02191Y0044D01*
X02349Y00111D02*
X02349Y00111D01*
X02191Y00111D02*
Y0044D01*
X01896Y01516D02*
X01897Y01516D01*
X01896Y00735D02*
Y01516D01*
X03018Y00111D02*
X03019Y00112D01*
X02703Y00111D02*
X02704Y00112D01*
X02711Y03002D02*
Y03003D01*
X02681Y02971D02*
X02711Y03002D01*
X02632Y02971D02*
X02681D01*
X03829Y03806D02*
X03944D01*
G54D26*
X01915Y00137D03*
X02545D03*
X02624D03*
X02899D03*
X03057D03*
X02742D03*
X02938D03*
X02781D03*
X02309D03*
X02427D03*
X02584D03*
X02072D03*
X02033D03*
X01994D03*
X01954D03*
X0219D03*
X02348D03*
X02387D03*
X02466D03*
X02505D03*
X0282D03*
X02663D03*
X0286D03*
X02978D03*
X03017D03*
X02702D03*
X02112D03*
X02151D03*
X01836D03*
X01875D03*
X03096D03*
G54D27*
X01797Y00157D03*
G54D33*
X02632Y03042D03*
Y02971D03*
G54D35*
X02341Y02854D03*
X02396D03*
G54D37*
X02712Y03043D03*
Y02988D03*
G54D77*
X02327Y02944D03*
X02398D03*
G54D81*
X02334Y03279D03*
Y032D03*
Y03121D03*
Y03042D03*
X02509Y03279D03*
Y03121D03*
Y032D03*
Y03042D03*
G54D142*
X00299Y02581D03*
Y02381D03*
X00099D03*
Y02581D03*
X00299Y02056D03*
Y01856D03*
X00099D03*
Y02056D03*
X00299Y01531D03*
Y01331D03*
X00099D03*
Y01531D03*
X00299Y01006D03*
Y00806D03*
X00099D03*
Y01006D03*
G54D162*
X02891Y00243D02*
D01*
X0289Y00244*
X02888Y00245*
X02887Y00246*
X02886Y00247*
X02885Y00247*
X02884Y00248*
X02882Y00248*
X02881Y00249*
X0288Y00249*
X02878Y00249*
X02878Y00249*
X02436Y00235D02*
D01*
X02435Y00234*
X02434Y00233*
X02433Y00232*
X02432Y00231*
X02431Y0023*
X0243Y00229*
X0243Y00228*
X02429Y00226*
X02429Y00225*
X02428Y00224*
X02428Y00222*
X02428Y00221*
X02427Y0022*
X02427Y00218*
X03889Y00771D02*
X04339Y0122D01*
X05964Y03555D02*
X06424Y03094D01*
Y02181D02*
Y03094D01*
Y03126*
X06132Y02548D02*
Y02653D01*
Y02548D02*
X06196Y02484D01*
X05994Y02791D02*
X06132Y02653D01*
X06409Y0122D02*
X06838Y01649D01*
X04339Y0122D02*
X06409D01*
X02719Y03786D02*
X02719Y03786D01*
X02878Y00249D02*
X02878D01*
X02891Y00243D02*
X02891Y00243D01*
X02898Y00235*
X02427Y00111D02*
Y00218D01*
X02436Y00235D02*
X02447Y00242D01*
X02624Y00235D02*
X02636Y00247D01*
X02799Y00251D02*
X02799D01*
X02546Y00111D02*
Y00244D01*
X03059Y00231D02*
X03079Y00251D01*
X03097*
X01849Y00269D02*
X01876Y00243D01*
X01916Y00111D02*
Y00244D01*
X02934Y00141D02*
Y00224D01*
X02782Y00235D02*
X02799Y00251D01*
X02742Y0024D02*
X02753Y00251D01*
X02923Y00235D02*
X02934Y00224D01*
X02624Y00111D02*
Y00235D01*
X03058Y00139D02*
X03059Y0014D01*
X02934Y00141D02*
X02938Y00137D01*
X02742D02*
Y0024D01*
X02753Y00251D02*
X02799D01*
X02898Y00138D02*
X02899Y00137D01*
X02898Y00138D02*
Y00235D01*
X02923*
X03058Y00111D02*
Y00139D01*
X03059Y0014D02*
Y00231D01*
X03057Y00111D02*
X03058Y00111D01*
X02782Y00139D02*
Y00235D01*
X02309Y00111D02*
Y00246D01*
X0219Y00112D02*
X02191Y00111D01*
X02781Y00137D02*
X02782Y00139D01*
X03057Y00137D02*
X03058Y00139D01*
X05985Y02782D02*
X05994Y02791D01*
X04511Y02782D02*
X05985D01*
X04503Y02789D02*
X04511Y02782D01*
X03157Y02485D02*
Y0318D01*
Y02485D02*
X03368Y02273D01*
X02774Y03562D02*
X03157Y0318D01*
X07004Y01611D02*
Y02546D01*
X06729Y01336D02*
X07004Y01611D01*
X06424Y03126D02*
X07004Y02546D01*
X02774Y03562D02*
Y03566D01*
X02114Y00288D02*
X02151Y00252D01*
X02112Y00255D02*
D01*
Y00137D02*
Y00255D01*
X02151Y00112D02*
Y00252D01*
X01876Y00111D02*
Y00243D01*
X01837Y00111D02*
Y00257D01*
X02151Y00112D02*
X02152Y00111D01*
X01837Y00257D02*
X01849Y00269D01*
X03219Y03806D02*
X03224Y03811D01*
X03218Y03805D02*
X03219Y03806D01*
X02722Y03786D02*
X02784D01*
X02719D02*
X02722D01*
X03571Y02033D02*
Y02058D01*
X02632Y03042D02*
X02638Y03036D01*
X02632Y03042D02*
X02632Y03042D01*
X02509Y03042D02*
X02632D01*
X02638Y03036D02*
X02711D01*
X03571Y0201D02*
Y02033D01*
X0358Y01878D02*
Y02001D01*
Y01878D02*
X03639Y01819D01*
X03571Y0201D02*
X0358Y02001D01*
X03559Y01739D02*
X03639Y01819D01*
X02998Y03811D02*
X03004Y03805D01*
X03218*
X02784Y03786D02*
X02809Y03811D01*
X03534D02*
X03539Y03806D01*
X03368Y02252D02*
X03549Y02071D01*
X03368Y02252D02*
Y02273D01*
X05274Y03511D02*
X05994Y02791D01*
X036Y0106D02*
Y01432D01*
X03559Y01473D02*
X036Y01432D01*
X03559Y01473D02*
Y01739D01*
X036Y0106D02*
X03889Y00771D01*
X04044Y03566D02*
X04254Y03776D01*
X02774Y03566D02*
X04044D01*
G54D166*
X00199Y02481D03*
Y01956D03*
Y01431D03*
Y00906D03*
G54D167*
X0299Y02437D03*
X03571Y02096D03*
Y01308D03*
X02202Y02437D03*
X01696Y01308D03*
Y02096D03*
X02202Y00957D03*
X0299D03*
G54D168*
X03784Y04126D03*
X03958D03*
G54D169*
X02994Y04086D03*
X03294D03*
G54D170*
X05327Y01007D03*
X04327Y02307D03*
X05127Y01007D03*
X04927D03*
X04727Y02307D03*
X04927D03*
X05127D03*
X05327D03*
G54D171*
X04327Y01007D03*
G54D172*
X04298Y02595D03*
X0418D03*
X04062D03*
X03979Y0089D03*
Y02489D03*
X05578D03*
Y01689D03*
Y0089D03*
G54D173*
X05723Y03844D03*
Y04025D03*
X06569Y03806D03*
Y03589D03*
X06734Y03806D03*
Y03589D03*
X069D03*
Y03806D03*
G54D174*
X06119Y03819D03*
G54D175*
X06119Y04056D03*
G54D176*
X05934Y03937D03*
G54D177*
X02043Y04057D03*
Y04157D03*
X01457Y04053D03*
Y04153D03*
G54D178*
X02043Y04257D03*
X01457Y04253D03*
G54D179*
X06569Y04093D03*
X069D03*
G54D180*
X00285Y04152D03*
Y00368D03*
G54D181*
X02645Y0227D03*
X02618Y02299D03*
X02671Y02291D03*
X06978Y0183D03*
X02314Y00933D03*
X02413D03*
X02515D03*
X02905Y00937D03*
X02901Y01106D03*
X0285D03*
X02787D03*
X02728D03*
X02665D03*
X0261D03*
X02511Y01105D03*
X02409Y01106D03*
X02311D03*
X02322Y02429D03*
X02421D03*
X02484D03*
X02783Y02433D03*
X02874Y0229D03*
X02779Y02601D03*
X02688D03*
X0259D03*
X02488Y02574D03*
X02385Y02613D03*
X02279Y02614D03*
X03051Y02732D03*
X03414Y02892D03*
Y02736D03*
X04385Y03661D03*
X04393Y03976D03*
X04318Y03507D03*
X04116Y03597D03*
X03657Y03296D03*
X03747Y01679D03*
X03718Y01713D03*
X03712Y01673D03*
X0359Y01662D03*
X04523Y03736D03*
X0307Y03393D03*
X04438Y03354D03*
X03542Y03318D03*
X03437Y03476D03*
X03622Y03486D03*
X04437Y03661D03*
X04053Y03641D03*
X0333Y03301D03*
X03344Y02996D03*
X03342Y02263D03*
X03368Y0305D03*
X01015Y01705D03*
X01721Y01685D03*
X01003Y01177D03*
X01893Y01685D03*
X0167D03*
X03877Y03078D03*
X03799Y03201D03*
X02633Y02921D03*
X02414Y03199D03*
X02413Y03295D03*
X02591Y03186D03*
X02462Y03172D03*
X0259Y03288D03*
X02418Y03118D03*
X0522Y04086D03*
X02258Y03741D03*
X0272Y03494D03*
X06335Y03147D03*
X06262Y0322D03*
X06287Y03195D03*
X06274Y02949D03*
X06362Y02952D03*
X0645Y02462D03*
Y02535D03*
X06452Y02606D03*
X06451Y02673D03*
X0645Y0274D03*
X06587Y01529D03*
X06594Y01673D03*
Y0161D03*
Y01775D03*
Y0172D03*
X03602Y00641D03*
X02948Y02456D03*
X02252Y02613D03*
X01674Y01989D03*
X03379Y01386D03*
X03732Y01418D03*
X02579Y02281D03*
X02708Y00976D03*
X02803Y02307D03*
X02575Y02412D03*
X03719Y01996D03*
X02685Y02311D03*
X03803Y01691D03*
X02958Y02621D03*
X0245Y02282D03*
X01714Y01595D03*
X03773Y01666D03*
X02606Y00931D03*
X02881Y02566D03*
X03554Y01941D03*
X0292Y02428D03*
X03864Y01511D03*
X03404Y01363D03*
X02841Y02263D03*
X02767Y00976D03*
X0341Y01713D03*
X03414Y01805D03*
X02799Y00976D03*
X03298Y01971D03*
X02894Y02431D03*
X02759Y00795D03*
X03571Y02058D03*
X02726Y02293D03*
X0274Y00976D03*
X02826Y00795D03*
X02821Y02601D03*
X02985Y02287D03*
X02494Y02696D03*
X01822Y01674D03*
X02625Y00795D03*
X03804Y0184D03*
X02702Y02289D03*
X02893Y00795D03*
X02732D03*
X02599Y02436D03*
X01718Y01792D03*
X02475Y02291D03*
X01879Y01811D03*
X03719Y01921D03*
X03554Y01891D03*
X01568Y02067D03*
X01675Y01891D03*
X01567Y01285D03*
X02826Y00976D03*
X02394Y0272D03*
X02942Y02286D03*
X03554Y01991D03*
X03571Y02033D03*
X02692Y00795D03*
X02598D03*
X01719Y01536D03*
X02272Y02463D03*
X02681Y00976D03*
X03594Y01514D03*
X02409Y02314D03*
X03406Y01461D03*
X03392Y01871D03*
X02494Y02661D03*
X03407Y01411D03*
X02499Y02236D03*
X02409Y02283D03*
X02649Y00976D03*
X01718Y01497D03*
X01619Y02121D03*
X02622Y00976D03*
X01798Y01304D03*
X01671Y01792D03*
X02665Y00795D03*
X01671Y01399D03*
X01754Y02126D03*
X02799Y00795D03*
X03924Y01536D03*
X03549Y01441D03*
X01897Y01516D03*
X02624Y02461D03*
X03329Y01826D03*
X03719Y01766D03*
X01884Y02071D03*
X03834Y01481D03*
X0167Y01595D03*
X02862Y00795D03*
X03894Y01566D03*
X01716Y01399D03*
X03224Y01661D03*
X03379Y01336D03*
X01671Y01497D03*
X0233Y02215D03*
X03413Y01573D03*
X03197Y01714D03*
X01721Y01989D03*
Y0189D03*
X03549Y01413D03*
X03439Y0187D03*
X03252Y01661D03*
X03554Y01841D03*
X04039Y03784D03*
X02692Y02721D03*
X02511Y00405D03*
X0261Y00279D03*
X02578D03*
X0298Y00409D03*
X02821Y00407D03*
X02748Y00282D03*
X02469Y0041D03*
X02905Y00279D03*
X02878Y00249D03*
X02854Y00405D03*
X02779Y00279D03*
X02665Y00405D03*
X02704D03*
X0235D03*
X02389D03*
X02937Y00279D03*
X02957Y00251D03*
X03019Y00405D03*
X02447Y00242D03*
X02413Y00279D03*
X02444D03*
X02636Y00247D03*
X02799Y00251D03*
X02546Y00244D03*
X03097Y00251D03*
X01797Y00355D03*
X02034Y00246D03*
X01916Y00244D03*
X02309Y00246D03*
X01393Y01816D03*
X0099Y00687D03*
X04794Y02808D03*
X03183Y03135D03*
X03277Y02963D03*
X03197Y0297D03*
X03491Y03103D03*
X03188Y03187D03*
X0323Y03235D03*
X03358Y03448D03*
X02419Y02788D03*
X02146Y02753D03*
X03275Y03141D03*
X03056Y01811D03*
X02254Y03536D03*
X02579Y03486D03*
X02389Y03481D03*
X02321Y03361D03*
X02434Y03546D03*
X02634Y03406D03*
X00996Y02256D03*
X02004Y01336D03*
X02028Y01361D03*
X02549Y01755D03*
X02473Y0298D03*
X02146Y04103D03*
X02253Y04086D03*
X01408Y0398D03*
X01345Y04175D03*
X00937Y02317D03*
X02353Y04017D03*
X01726Y04329D03*
X01788D03*
X04477Y03135D03*
X04064Y02722D03*
X06628Y01372D03*
X04039Y02406D03*
X04134Y01651D03*
X03994Y01551D03*
X04134Y01751D03*
X04151Y01623D03*
X03968Y01671D03*
X03969Y01552D03*
X03944Y01816D03*
X04131Y01686D03*
X04179Y01601D03*
X04034Y01546D03*
X03996Y01711D03*
X04064Y01796D03*
Y01511D03*
X03263Y03303D03*
X0396Y02724D03*
X01569Y04171D03*
X02076Y00255D03*
Y00287D03*
X02112D03*
X02151D03*
X02112Y00255D03*
X02151D03*
X01832D03*
X01852D03*
X01872D03*
X01832Y00287D03*
X01852D03*
X01872D03*
X06647Y03129D03*
X04339Y02725D03*
X04503Y02789D03*
X03829Y03806D03*
X05577Y02214D03*
X02694Y01481D03*
X02384Y01941D03*
X0383Y03762D03*
X06334Y03266D03*
X03744Y03261D03*
X03395Y04222D03*
X04272Y03135D03*
X05634Y02236D03*
X02626Y0177D03*
X06304Y03121D03*
X03939D03*
X04208Y03135D03*
X02604Y01734D03*
X06649Y03003D03*
X04152Y03135D03*
X02299Y01916D03*
X01248Y02D03*
X02579Y0179D03*
X04068Y03135D03*
X02674Y03501D03*
X04234Y02725D03*
X06456Y03009D03*
X01691Y04079D03*
X02259Y03261D03*
X03374Y03273D03*
X06476Y03231D03*
X04333Y03135D03*
X01557Y04229D03*
X03806Y03235D03*
X01261Y02482D03*
X04114Y03135D03*
X06648Y03341D03*
X02888Y04221D03*
X01749Y0411D03*
X0257Y04283D03*
X01459Y03147D03*
X0144Y03557D03*
X01903Y04018D03*
X0229Y04217D03*
X03623Y02587D03*
X03491Y03297D03*
X03744Y03342D03*
X03394Y03447D03*
X03717Y03072D03*
X02799Y03616D03*
X03589Y01711D03*
X05733Y03556D03*
X05676Y03546D03*
X03603Y00682D03*
X02478Y00937D03*
X06694Y0183D03*
X06699Y01881D03*
X06949Y02095D03*
X06607Y02176D03*
X06395Y02111D03*
X06048Y02171D03*
X06003Y0243D03*
X06274Y02391D03*
X0491Y04203D03*
X04387Y04206D03*
X03777Y04023D03*
X04085Y03892D03*
X04194Y03884D03*
X04431Y03135D03*
X0286Y03787D03*
X02724Y03729D03*
X03531Y0366D03*
X03269Y03788D03*
X01242Y01472D03*
X01256Y00942D03*
X00654Y0079D03*
X00655Y01028D03*
X00654Y01314D03*
X00653Y01551D03*
X00654Y01839D03*
Y02073D03*
Y02365D03*
X00653Y02593D03*
X02206Y01298D03*
X02205Y032D03*
X02502Y01316D03*
X02525Y02463D03*
X03498Y02341D03*
X02429Y02621D03*
X01004Y00906D03*
X02446Y01437D03*
X01008Y0143D03*
X02409Y01967D03*
X01009Y01956D03*
X0102Y02481D03*
X02643Y01616D03*
X02666Y0164D03*
X01884Y03601D03*
X01754Y03661D03*
X03424Y03636D03*
X01549Y03621D03*
X03239Y03596D03*
X01574D03*
X03539Y03806D03*
X03219D03*
X02722Y03786D03*
X02139Y03611D03*
X02084Y03896D03*
X02083Y01411D03*
X02059Y01386D03*
Y03871D03*
X02029Y03836D03*
X01294Y04256D03*
X02004Y03816D03*
X05274Y03511D03*
X02679Y03661D03*
X02774Y03566D03*
X02993Y03751D03*
X03699D03*
X03014Y03831D03*
X03699Y03836D03*
X04254Y03776D03*
X02894Y01561D03*
X02919Y01536D03*
X02274Y01506D03*
X02719Y01591D03*
X06424Y02181D03*
X04754Y04115D03*
X01779Y04156D03*
X03504Y04086D03*
X03854Y03151D03*
X03829Y03176D03*
X06439Y03191D03*
X06354Y03331D03*
X06444Y03291D03*
X03302Y03344D03*
X06409Y03371D03*
X06447Y03396D03*
X06479Y03426D03*
X06509Y03456D03*
X03469D03*
X01849Y03701D03*
X06294D03*
G54D182*
X05964Y03555D03*
X06196Y02484D03*
X06838Y01649D03*
G54D183*
X02531Y03853D03*
Y0283D03*
X00149D03*
Y03853D03*
G54D184*
X02349Y00362D03*
Y00329D03*
X02389D03*
Y00362D03*
X02468D03*
Y00329D03*
X02511D03*
Y00362D03*
X02664Y00329D03*
Y00362D03*
X02704Y00329D03*
Y00362D03*
X02819Y00329D03*
Y00362D03*
X02854D03*
Y00329D03*
X02979D03*
Y00362D03*
X03019Y00329D03*
Y00362D03*
G54D185*
X0213Y00268D03*
X01851Y00269D03*
M02*